G04 ================== begin FILE IDENTIFICATION RECORD ==================*
G04 Layout Name:  13948-1b.brd*
G04 Film Name:    DIF_REF_BOTTOM*
G04 File Format:  Gerber RS274X*
G04 File Origin:  Cadence Allegro 16.5-S045*
G04 Origin Date:  Thu Nov 13 15:49:17 2014*
G04 *
G04 Layer:  BOARD GEOMETRY/OUTLINE*
G04 Layer:  BOARD GEOMETRY/DIF_REF_BOTTOM*
G04 Layer:  BOARD GEOMETRY/PANEL_OUTLINE*
G04 *
G04 Offset:    (0.00 0.00)*
G04 Mirror:    No*
G04 Mode:      Positive*
G04 Rotation:  0*
G04 FullContactRelief:  No*
G04 UndefLineWidth:     6.00*
G04 ================== end FILE IDENTIFICATION RECORD ====================*
%FSLAX35Y35*MOIN*%
%IR0*IPPOS*OFA0.00000B0.00000*MIA0B0*SFA1.00000B1.00000*%
%ADD10C,.004*%
%ADD11C,.006*%
%ADD12C,.0035*%
%ADD13C,.0055*%
G75*
%LPD*%
G75*
G54D10*
G01X47476Y397029D02*
G02X46480Y398712I2775J2778D01*
G01D02*
G02X46353Y399340I3772J1090D01*
G01D02*
G02X46326Y399805I3899J460D01*
G01D02*
Y414860D01*
G01X47476Y393529D02*
X47483Y393522D01*
G01D02*
Y387776D01*
G01X43976Y393529D02*
Y387862D01*
G01D02*
X43883Y387769D01*
G01X43976Y397029D02*
X44801Y397855D01*
G01D02*
G03X44976Y398276I-421J422D01*
G01D02*
Y414860D01*
G01X46326D02*
G02X47785Y418382I4981J0D01*
G01X44976Y414860D02*
G02X46830Y419337I6331J1D01*
G01X47785Y418382D02*
X60904Y431501D01*
G01X46830Y419337D02*
X59949Y432456D01*
G01X66476Y397029D02*
X65753Y397752D01*
G01D02*
G02X65246Y398976I1224J1224D01*
G01D02*
Y411769D01*
G01X66476Y393529D02*
Y387883D01*
G01D02*
X66483Y387876D01*
G01X62976Y393529D02*
Y388242D01*
G01D02*
G02X62783Y387776I-659J0D01*
G01X62976Y397029D02*
G03X63860Y398783I-2222J2220D01*
G01D02*
G03X63870Y398851I-3102J491D01*
G01D02*
G03X63889Y399060I-3116J389D01*
G01D02*
G03X63896Y399250I-3133J211D01*
G01D02*
Y411770D01*
G01X56976Y397029D02*
G02X56045Y397414I-1J1316D01*
G01D02*
X55881Y397579D01*
G01D02*
X55603Y397858D01*
G01D02*
G02X55483Y398148I290J290D01*
G01D02*
Y414134D01*
G01X56976Y393529D02*
Y387969D01*
G01D02*
X56883Y387876D01*
G01X53476Y393529D02*
Y388383D01*
G01D02*
G02X53183Y387676I-1000J0D01*
G01X53476Y397029D02*
G03X54133Y398615I-1586J1586D01*
G01D02*
Y414135D01*
G01X65246Y411769D02*
G02X66901Y415763I5649J-1D01*
G01D02*
X67144Y416006D01*
G01D02*
G02X76304Y419800I9160J-9161D01*
G01X63896Y411770D02*
G02X65946Y416718I6999J-1D01*
G01D02*
X66189Y416961D01*
G01D02*
G02X76303Y421150I10114J-10116D01*
G01X55483Y414134D02*
G02X56771Y417242I4396J-1D01*
G01D02*
X58724Y419196D01*
G01X54133Y414135D02*
G02X55816Y418197I5746J-1D01*
G01X58724Y419196D02*
X61908Y422380D01*
G01D02*
G02X78120Y429095I16212J-16213D01*
G01X55816Y418197D02*
X57769Y420151D01*
G01D02*
X60953Y423335D01*
G01D02*
G02X78119Y430445I17166J-17168D01*
G01X60904Y431501D02*
G02X73564Y436745I12660J-12660D01*
G01X59949Y432456D02*
G02X73563Y438095I13614J-13615D01*
G01X73083Y401900D02*
Y399156D01*
G01D02*
G02X72362Y397415I-2462J0D01*
G01D02*
X71976Y397029D01*
G01Y393529D02*
Y388201D01*
G01D02*
G02X71883Y387976I-318J0D01*
G01X75476Y393529D02*
Y389441D01*
G01D02*
G03X76083Y387976I2072J0D01*
G01X75476Y397029D02*
X74590Y398770D01*
G01D02*
G02X74455Y399244I1150J584D01*
G01D02*
X74433Y399495D01*
G01D02*
G02Y399547I3561J26D01*
G01D02*
Y401900D01*
G01X96696Y409050D02*
X82110D01*
G01D02*
G03X75845Y406455I0J-8861D01*
G01D02*
X74350Y404960D01*
G01D02*
G03X73083Y401900I3060J-3059D01*
G01X74433D02*
G02X75305Y404005I2977J0D01*
G01D02*
X76800Y405500D01*
G01D02*
G02X82111Y407700I5311J-5311D01*
G01D02*
X136219D01*
G01X76304Y419800D02*
X77504D01*
G01D02*
G02X78444Y419330I18J-1140D01*
G01D02*
G03X79384Y418860I922J670D01*
G01D02*
X80584D01*
G01D02*
G03X81524Y419330I18J1140D01*
G01D02*
G02X82464Y419800I922J-670D01*
G01D02*
X83664D01*
G01X76303Y421150D02*
X134620D01*
G01X78120Y429095D02*
X135424D01*
G01X78119Y430445D02*
X135425D01*
G01X73564Y436745D02*
X138274D01*
G01X73563Y438095D02*
X138275D01*
G01X100716Y409520D02*
G03X99776Y409990I-922J-670D01*
G01D02*
X98576D01*
G01D02*
G03X97636Y409520I-18J-1140D01*
G01D02*
G02X96696Y409050I-922J670D01*
G01X83664Y419800D02*
G02X84604Y419330I18J-1140D01*
G01D02*
G03X85544Y418860I922J670D01*
G01D02*
X86744D01*
G01D02*
G03X87684Y419330I18J1140D01*
G01D02*
G02X88624Y419800I922J-670D01*
G01D02*
X89824D01*
G01D02*
G02X90764Y419330I18J-1140D01*
G01D02*
G03X91704Y418860I922J670D01*
G01D02*
X92904D01*
G01D02*
G03X93844Y419330I18J1140D01*
G01D02*
G02X94784Y419800I922J-670D01*
G01D02*
X101488D01*
G01X136220Y409050D02*
X107816D01*
G01D02*
G02X106876Y409520I-18J1140D01*
G01D02*
G03X105936Y409990I-922J-670D01*
G01D02*
X104736D01*
G01D02*
G03X103796Y409520I-18J-1140D01*
G01D02*
G02X102856Y409050I-922J670D01*
G01D02*
X101656D01*
G01D02*
G02X100716Y409520I-18J1140D01*
G01X101488Y419800D02*
G02X102428Y419330I18J-1140D01*
G01D02*
G03X103368Y418860I923J670D01*
G01D02*
X104568D01*
G01D02*
G03X105508Y419330I18J1140D01*
G01D02*
G02X106448Y419800I923J-670D01*
G01D02*
X111506D01*
G01D02*
G02X112446Y419330I18J-1140D01*
G01D02*
G03X113386Y418860I922J670D01*
G01D02*
X114586D01*
G01D02*
G03X115526Y419330I18J1140D01*
G01D02*
G02X116466Y419800I922J-670D01*
G01D02*
X134619D01*
G01X184086Y363814D02*
X140710Y407190D01*
G01X139754Y406236D02*
X183130Y362860D01*
G01X138154Y418336D02*
X186630Y369860D01*
G01X139110Y419290D02*
X187585Y370815D01*
G01X140710Y407190D02*
G03X136220Y409050I-4490J-4490D01*
G01X136219Y407700D02*
G02X139754Y406236I0J-5000D01*
G01X138959Y427631D02*
X189730Y376860D01*
G01X134619Y419800D02*
G02X138154Y418336I0J-5000D01*
G01X134620Y421150D02*
G02X139110Y419290I0J-6350D01*
G01X135424Y429095D02*
G02X138959Y427631I0J-5000D01*
G01X135425Y430445D02*
G02X139915Y428585I0J-6350D01*
G01D02*
X190685Y377815D01*
G01X141809Y435281D02*
X192730Y384360D01*
G01X142765Y436235D02*
X193686Y385314D01*
G01X138274Y436745D02*
G02X141809Y435281I0J-5000D01*
G01X138275Y438095D02*
G02X142765Y436235I0J-6350D01*
G01X166924Y295440D02*
X165793Y294309D01*
G01X155874Y317807D02*
X157122Y316559D01*
G01D02*
X163374D01*
G01D02*
G02X168470Y311463I0J-5096D01*
G01X155874Y313961D02*
X157122Y315209D01*
G01D02*
X163374D01*
G01D02*
G02X167120Y311463I0J-3746D01*
G01X165795Y303959D02*
X166156Y303598D01*
G01X155874Y323111D02*
X157122Y324359D01*
G01D02*
X168724D01*
G01X155874Y326957D02*
X157122Y325709D01*
G01D02*
X168724D01*
G01X175940Y303314D02*
G02X176490Y301987I-1327J-1328D01*
G01D02*
Y296323D01*
G01D02*
G02X176373Y296040I-401J0D01*
G01D02*
X175242Y294909D01*
G01X178756Y303419D02*
G03X177840Y301209I2210J-2211D01*
G01D02*
Y296323D01*
G01D02*
G03X177957Y296040I401J0D01*
G01D02*
X179088Y294909D01*
G01X169795Y303959D02*
G03X168391Y300569I3390J-3390D01*
G01D02*
Y295723D01*
G01D02*
G03X168508Y295440I401J0D01*
G01D02*
X169639Y294309D01*
G01X166156Y303598D02*
G02X167041Y301461I-2138J-2137D01*
G01D02*
Y295723D01*
G01D02*
G02X166924Y295440I-401J0D01*
G01X175295Y303959D02*
X175940Y303314D01*
G01X168724Y324359D02*
G02X176374Y316709I0J-7650D01*
G01D02*
Y309788D01*
G01D02*
X175295Y308709D01*
G01D02*
Y307459D01*
G01X168724Y325709D02*
G02X177724Y316709I0J-9000D01*
G01D02*
Y309859D01*
G01D02*
X179295Y308288D01*
G01D02*
Y307459D01*
G01Y303959D02*
X178756Y303419D01*
G01X168470Y311463D02*
Y310009D01*
G01D02*
G03X168870Y309609I400J0D01*
G01D02*
X169395D01*
G01D02*
G02X169795Y309209I0J-400D01*
G01D02*
Y307459D01*
G01X167120Y311463D02*
Y310009D01*
G01D02*
G02X166720Y309609I-400J0D01*
G01D02*
X166195D01*
G01D02*
G03X165795Y309209I0J-400D01*
G01D02*
Y307459D01*
G01X192874Y330461D02*
X193591Y331177D01*
G01D02*
G02X194874Y331709I1284J-1283D01*
G01D02*
X208046D01*
G01X208047Y333059D02*
X194874D01*
G01D02*
G02X193591Y333591I1J1815D01*
G01D02*
X192874Y334307D01*
G01X206874Y342709D02*
X195525D01*
G01D02*
G03X192874Y341611I0J-3749D01*
G01X206874Y344059D02*
X196249D01*
G01D02*
G02X192874Y345457I0J4773D01*
G01X186630Y369860D02*
G03X191120Y368000I4490J4490D01*
G01D02*
X210501D01*
G01X205843Y362350D02*
X187621D01*
G01D02*
G02X184086Y363814I0J5000D01*
G01X183130Y362860D02*
G03X187620Y361000I4490J4490D01*
G01D02*
X205844D01*
G01X187585Y370815D02*
G03X191121Y369350I3536J3535D01*
G01D02*
X210500D01*
G01X189730Y376860D02*
G03X194220Y375000I4490J4490D01*
G01D02*
X214404D01*
G01X190685Y377815D02*
G03X194221Y376350I3536J3535D01*
G01D02*
X214405D01*
G01X192730Y384360D02*
G03X197220Y382500I4490J4490D01*
G01D02*
X219490D01*
G01X193686Y385314D02*
G03X197221Y383850I3535J3536D01*
G01D02*
X219491D01*
G01X209795Y300459D02*
X210813Y299441D01*
G01D02*
G02X211135Y298664I-776J-777D01*
G01D02*
Y296323D01*
G01D02*
G02X211018Y296040I-401J0D01*
G01D02*
X209887Y294909D01*
G01X213795Y300459D02*
X213150Y299813D01*
G01D02*
G03X212485Y298209I1604J-1605D01*
G01D02*
Y296323D01*
G01D02*
G03X212602Y296040I401J0D01*
G01D02*
X213733Y294909D01*
G01X200295Y300459D02*
X201384Y299370D01*
G01D02*
G02X201687Y298638I-733J-732D01*
G01D02*
Y296323D01*
G01D02*
G02X201570Y296040I-401J0D01*
G01D02*
X200439Y294909D01*
G01X203795Y300459D02*
G03X203037Y298629I1830J-1830D01*
G01D02*
Y296323D01*
G01D02*
G03X203154Y296040I401J0D01*
G01D02*
X204285Y294909D01*
G01X209795Y303959D02*
Y305709D01*
G01D02*
G02X210195Y306109I400J0D01*
G01D02*
X210720D01*
G01D02*
G03X211120Y306509I0J400D01*
G01D02*
Y308709D01*
G01D02*
G02X213470Y311059I2350J0D01*
G01D02*
X221874D01*
G01X213795Y303959D02*
Y305709D01*
G01D02*
G03X213395Y306109I-400J0D01*
G01D02*
X212870D01*
G01D02*
G02X212470Y306509I0J400D01*
G01D02*
Y308709D01*
G01D02*
G02X213470Y309709I1000J0D01*
G01D02*
X221874D01*
G01X216374Y318059D02*
X213653D01*
G01D02*
G03X203687Y313932I-2J-14092D01*
G01D02*
G03X201524Y308709I5223J-5222D01*
G01D02*
Y306709D01*
G01D02*
X200295Y305480D01*
G01D02*
Y303959D01*
G01X203795D02*
Y305788D01*
G01D02*
X202874Y306709D01*
G01D02*
Y308709D01*
G01D02*
G02X204642Y312977I6036J0D01*
G01D02*
G02X213652Y316709I9010J-9010D01*
G01D02*
X216374D01*
G01X208046Y331709D02*
G02X212874Y329709I0J-6828D01*
G01D02*
X216874Y325709D01*
G01X217829Y326664D02*
X213829Y330664D01*
G01D02*
G03X208047Y333059I-5783J-5783D01*
G01X221056Y333098D02*
X214677Y339477D01*
G01D02*
G03X206874Y342709I-7803J-7803D01*
G01X215632Y340432D02*
G03X206874Y344059I-8757J-8759D01*
G01X210501Y368000D02*
G02X218182Y364818I-1J-10864D01*
G01X216455Y357955D02*
G03X205843Y362350I-10611J-10612D01*
G01X205844Y361000D02*
G02X215500Y357000I-1J-13657D01*
G01X210500Y369350D02*
G02X219137Y365773I1J-12214D01*
G01X214404Y375000D02*
G02X222250Y371750I0J-11096D01*
G01X214405Y376350D02*
G02X223205Y372705I0J-12446D01*
G01X221874Y311059D02*
G03X224945Y314130I0J3071D01*
G01D02*
Y323709D01*
G01X221874Y309709D02*
G03X226295Y314130I0J4421D01*
G01D02*
Y323709D01*
G01X217874Y319559D02*
G02X216374Y318059I-1500J0D01*
G01Y316709D02*
G03X219224Y319559I0J2850D01*
G01X224945Y323709D02*
G03X221056Y333098I-13278J0D01*
G01X226295Y323709D02*
G03X222011Y334053I-14628J1D01*
G01D02*
X215632Y340432D01*
G01X216874Y325709D02*
G02X217873Y323296I-2413J-2412D01*
G01D02*
X217874Y323297D01*
G01D02*
Y319559D01*
G01X219224D02*
Y323296D01*
G01D02*
G03X217829Y326664I-4763J0D01*
G01X218182Y364818D02*
X282255Y300745D01*
G01X276459Y297951D02*
X216455Y357955D01*
G01X215500Y357000D02*
X275505Y296995D01*
G01X219137Y365773D02*
X283209Y301701D01*
G01X222250Y371750D02*
X289005Y304995D01*
G01X223205Y372705D02*
X271467Y324443D01*
G01X219490Y382500D02*
G02X229750Y378250I0J-14510D01*
G01D02*
X241877Y366123D01*
G01X219491Y383850D02*
G02X230705Y379205I0J-15860D01*
G01D02*
X296990Y312920D01*
G01X241877Y366123D02*
G02X242210Y365126I-793J-819D01*
G01D02*
G03X242542Y364129I1126J-179D01*
G01D02*
X243391Y363280D01*
G01D02*
G03X244388Y362948I818J794D01*
G01D02*
G02X245385Y362615I178J-1126D01*
G01D02*
X256869Y351131D01*
G01D02*
G02X257201Y350134I-794J-818D01*
G01D02*
G03X257533Y349137I1126J-179D01*
G01D02*
X258382Y348289D01*
G01D02*
G03X259379Y347956I819J793D01*
G01D02*
G02X260376Y347624I179J-1126D01*
G01D02*
X261225Y346775D01*
G01D02*
G02X261557Y345778I-794J-818D01*
G01D02*
G03X261889Y344781I1126J-179D01*
G01D02*
X262738Y343933D01*
G01D02*
G03X263735Y343601I818J794D01*
G01D02*
G02X264732Y343268I178J-1126D01*
G01X338268Y151231D02*
X279000Y210500D01*
G01D02*
G02X278319Y212144I1644J1644D01*
G01D02*
Y293461D01*
G01X276969Y293460D02*
Y212143D01*
G01D02*
G03X278045Y209545I3675J0D01*
G01D02*
X337313Y150276D01*
G01X278319Y293461D02*
G03X276459Y297951I-6350J0D01*
G01X275505Y296995D02*
G02X276969Y293460I-3536J-3535D01*
G01X277817Y319423D02*
X278665Y318574D01*
G01D02*
G02X278997Y317577I-794J-818D01*
G01D02*
G03X279330Y316580I1126J-178D01*
G01D02*
X280178Y315732D01*
G01D02*
G03X281175Y315399I819J793D01*
G01X271467Y324443D02*
G03X272464Y324111I818J794D01*
G01D02*
G02X273461Y323779I179J-1126D01*
G01D02*
X274309Y322930D01*
G01D02*
G02X274642Y321933I-793J-819D01*
G01D02*
G03X274974Y320936I1126J-179D01*
G01D02*
X275823Y320087D01*
G01D02*
G03X276820Y319755I818J794D01*
G01D02*
G02X277817Y319423I179J-1126D01*
G01X269088Y338912D02*
X296036Y311964D01*
G01X264732Y343268D02*
X265580Y342420D01*
G01D02*
G02X265913Y341423I-793J-819D01*
G01D02*
G03X266245Y340426I1126J-179D01*
G01D02*
X267094Y339577D01*
G01D02*
G03X268091Y339245I818J794D01*
G01D02*
G02X269088Y338912I178J-1126D01*
G01X285545Y212045D02*
X337624Y159966D01*
G01X286500Y213000D02*
X338579Y160921D01*
G01X283719Y297210D02*
Y216455D01*
G01D02*
G03X285545Y212045I6236J-1D01*
G01X285069Y297211D02*
Y216455D01*
G01D02*
G03X286500Y213000I4886J0D01*
G01X290469Y301460D02*
Y220030D01*
G01D02*
G03X292148Y215975I5734J-1D01*
G01D02*
X294812Y213312D01*
G01D02*
X329948Y178176D01*
G01X291819Y301461D02*
Y220030D01*
G01D02*
G03X293103Y216930I4384J0D01*
G01D02*
X295767Y214267D01*
G01D02*
X330864Y179170D01*
G01X282255Y300745D02*
G02X283719Y297210I-3536J-3535D01*
G01X283209Y301701D02*
G02X285069Y297211I-4490J-4490D01*
G01X289005Y304995D02*
G02X290469Y301460I-3536J-3535D01*
G01X289959Y305951D02*
G02X291819Y301461I-4490J-4490D01*
G01X281175Y315399D02*
G02X282172Y315067I179J-1126D01*
G01D02*
X283021Y314219D01*
G01D02*
G02X283353Y313221I-794J-818D01*
G01D02*
G03X283686Y312224I1126J-178D01*
G01D02*
X289959Y305951D01*
G01X296036Y311964D02*
G02X297500Y308429I-3536J-3535D01*
G01X296990Y312920D02*
G02X298850Y308430I-4490J-4490D01*
G01X288328Y879314D02*
G03X291545Y871545I10985J-2D01*
G01D02*
X332045Y831045D01*
G01X289678Y879313D02*
G03X292500Y872500I9635J0D01*
G01D02*
X333000Y832000D01*
G01X288328Y1000344D02*
Y879314D01*
G01X289678Y894760D02*
G03X290148Y893820I1140J-18D01*
G01D02*
G02X290618Y892880I-670J-922D01*
G01D02*
Y891680D01*
G01D02*
G02X290148Y890740I-1140J-18D01*
G01D02*
G03X289678Y889800I670J-922D01*
G01D02*
Y879313D01*
G01Y914760D02*
Y894760D01*
G01Y927080D02*
Y925880D01*
G01D02*
G03X290148Y924940I1140J-18D01*
G01D02*
G02X290618Y924000I-670J-922D01*
G01D02*
Y922800D01*
G01D02*
G02X290148Y921860I-1140J-18D01*
G01D02*
G03X289678Y920920I670J-922D01*
G01D02*
Y919720D01*
G01D02*
G03X290148Y918780I1140J-18D01*
G01D02*
G02X290618Y917840I-670J-922D01*
G01D02*
Y916640D01*
G01D02*
G02X290148Y915700I-1140J-18D01*
G01D02*
G03X289678Y914760I670J-922D01*
G01Y952040D02*
Y932040D01*
G01D02*
G03X290148Y931100I1140J-18D01*
G01D02*
G02X290618Y930160I-670J-922D01*
G01D02*
Y928960D01*
G01D02*
G02X290148Y928020I-1140J-18D01*
G01D02*
G03X289678Y927080I670J-922D01*
G01X290618Y960080D02*
G02X290148Y959140I-1140J-18D01*
G01D02*
G03X289678Y958200I670J-922D01*
G01D02*
Y957000D01*
G01D02*
G03X290148Y956060I1140J-18D01*
G01D02*
G02X290618Y955120I-670J-922D01*
G01D02*
Y953920D01*
G01D02*
G02X290148Y952980I-1140J-18D01*
G01D02*
G03X289678Y952040I670J-922D01*
G01Y998688D02*
Y969320D01*
G01D02*
G03X290148Y968380I1140J-18D01*
G01D02*
G02X290618Y967440I-670J-922D01*
G01D02*
Y966240D01*
G01D02*
G02X290148Y965300I-1140J-18D01*
G01D02*
G03X289678Y964360I670J-922D01*
G01D02*
Y963160D01*
G01D02*
G03X290148Y962220I1140J-18D01*
G01D02*
G02X290618Y961280I-670J-922D01*
G01D02*
Y960080D01*
G01X287403Y1009860D02*
Y1002677D01*
G01D02*
G03X288041Y1001137I2178J0D01*
G01D02*
G02X288231Y1000678I-459J-459D01*
G01D02*
G03X288285Y1000489I358J0D01*
G01D02*
X288309Y1000450D01*
G01D02*
G02X288328Y1000344I-309J-110D01*
G01X291338Y1009860D02*
Y1003196D01*
G01D02*
G02X290606Y1001428I-2501J0D01*
G01D02*
X289868Y999644D01*
G01D02*
G03X289678Y998688I2310J-956D01*
G01X332309Y130450D02*
X310029D01*
G01D02*
Y130449D01*
G01D02*
G02X307534Y131483I-1J3524D01*
G01D02*
X307420Y131599D01*
G01D02*
X302181Y136838D01*
G01D02*
G02X301079Y139500I2663J2661D01*
G01X331628Y131800D02*
X310029D01*
G01D02*
G02X308492Y132436I-1J2173D01*
G01D02*
X308379Y132550D01*
G01D02*
X303136Y137793D01*
G01D02*
G02X302429Y139500I1707J1707D01*
G01X313597Y137400D02*
G02X311023Y138465I-1J3640D01*
G01D02*
X310744Y138746D01*
G01X301079Y139500D02*
Y142478D01*
G01D02*
G03X301019Y142782I-800J0D01*
G01D02*
X300828Y143245D01*
G01D02*
G03X300654Y143506I-740J-305D01*
G01D02*
X299831Y144328D01*
G01X302429Y139500D02*
Y143369D01*
G01D02*
G02X302663Y143934I799J0D01*
G01D02*
X302823Y144094D01*
G01D02*
G02X303388Y144328I565J-565D01*
G01D02*
X303677D01*
G01X313598Y138750D02*
G02X311979Y139420I-1J2289D01*
G01D02*
X311700Y139700D01*
G01D02*
G02X311100Y141149I1449J1449D01*
G01D02*
Y143875D01*
G01D02*
G03X310163Y146137I-3199J0D01*
G01D02*
G02X308451Y150270I4133J4133D01*
G01D02*
X308450Y162386D01*
G01X310744Y138746D02*
G02X309750Y141149I2405J2402D01*
G01D02*
Y143874D01*
G01D02*
G03X309208Y145182I-1849J0D01*
G01D02*
G02X307100Y150270I5088J5088D01*
G01D02*
Y162386D01*
G01X313402Y156000D02*
X313989Y155413D01*
G01X308450Y162386D02*
G02X308567Y162669I401J0D01*
G01D02*
X309698Y163800D01*
G01X307100Y162386D02*
G03X306983Y162669I-401J0D01*
G01D02*
X305852Y163800D01*
G01X297499Y223500D02*
G03X299620Y218378I7242J-1D01*
G01D02*
X300500Y217500D01*
G01D02*
X343000Y175000D01*
G01X298850Y223500D02*
G03X300575Y219334I5891J-1D01*
G01D02*
X301455Y218455D01*
G01D02*
X344350Y175560D01*
G01X297500Y308429D02*
Y223500D01*
G01D02*
X297499D01*
G01X298850Y308430D02*
Y223500D01*
G01X306545Y867045D02*
X339545Y834045D01*
G01X304328Y997995D02*
Y872399D01*
G01D02*
G03X306545Y867045I7571J-1D01*
G01X305678Y896682D02*
Y872399D01*
G01D02*
G03X307500Y868000I6221J0D01*
G01D02*
X340500Y835000D01*
G01X305678Y931698D02*
Y907802D01*
G01D02*
G03X306148Y906862I1140J-18D01*
G01D02*
G02X306618Y905922I-670J-922D01*
G01D02*
Y904722D01*
G01D02*
G02X306148Y903782I-1140J-18D01*
G01D02*
G03X305678Y902842I670J-922D01*
G01D02*
Y901642D01*
G01D02*
G03X306148Y900702I1140J-18D01*
G01D02*
G02X306618Y899762I-670J-922D01*
G01D02*
Y898562D01*
G01D02*
G02X306148Y897622I-1140J-18D01*
G01D02*
G03X305678Y896682I670J-922D01*
G01Y944018D02*
Y942818D01*
G01D02*
G03X306148Y941878I1140J-18D01*
G01D02*
G02X306618Y940938I-670J-923D01*
G01D02*
Y939738D01*
G01D02*
G02X306148Y938798I-1140J-18D01*
G01D02*
G03X305678Y937858I670J-923D01*
G01D02*
Y936658D01*
G01D02*
G03X306148Y935718I1140J-18D01*
G01D02*
G02X306618Y934778I-670J-923D01*
G01D02*
Y933578D01*
G01D02*
G02X306148Y932638I-1140J-18D01*
G01D02*
G03X305678Y931698I670J-923D01*
G01Y968978D02*
Y948978D01*
G01D02*
G03X306148Y948038I1140J-18D01*
G01D02*
G02X306618Y947098I-670J-923D01*
G01D02*
Y945898D01*
G01D02*
G02X306148Y944958I-1140J-18D01*
G01D02*
G03X305678Y944018I670J-923D01*
G01X306148Y976078D02*
G03X305678Y975138I670J-923D01*
G01D02*
Y973938D01*
G01D02*
G03X306148Y972998I1140J-18D01*
G01D02*
G02X306618Y972058I-670J-923D01*
G01D02*
Y970858D01*
G01D02*
G02X306148Y969918I-1140J-18D01*
G01D02*
G03X305678Y968978I670J-923D01*
G01Y997310D02*
Y980098D01*
G01D02*
G03X306148Y979158I1140J-18D01*
G01D02*
G02X306618Y978218I-670J-923D01*
G01D02*
Y977018D01*
G01D02*
G02X306148Y976078I-1140J-18D01*
G01X302978Y1009450D02*
Y1001255D01*
G01D02*
G03X303653Y999625I2306J0D01*
G01D02*
G02X304327Y997998I-1631J-1629D01*
G01D02*
G02X304328Y997995I-2075J-693D01*
G01X307088Y1009860D02*
Y1001916D01*
G01D02*
G02X306923Y1001022I-2500J-1D01*
G01D02*
X305843Y998204D01*
G01D02*
G03X305678Y997310I2335J-893D01*
G01X303148Y1009860D02*
G03X302978Y1009450I409J-410D01*
G01X327100Y136294D02*
X326111Y137283D01*
G01D02*
G03X325828Y137400I-283J-284D01*
G01D02*
X313597D01*
G01X330271Y151400D02*
X327429D01*
G01D02*
G02X326422Y152407I0J1007D01*
G01D02*
Y152507D01*
G01X330129Y150050D02*
X327464D01*
G01D02*
G03X326422Y149008I0J-1042D01*
G01D02*
Y148944D01*
G01X313989Y155413D02*
G02X314450Y154300I-1113J-1113D01*
G01D02*
Y146650D01*
G01D02*
G03X316800Y144300I2350J0D01*
G01D02*
X318386D01*
G01D02*
G02X318669Y144183I0J-401D01*
G01D02*
X319800Y143052D01*
G01X317248Y156000D02*
X315978Y154730D01*
G01D02*
G03X315800Y154300I430J-430D01*
G01D02*
Y146650D01*
G01D02*
G03X316800Y145650I1000J0D01*
G01D02*
X318386D01*
G01D02*
G03X318669Y145767I0J401D01*
G01D02*
X319800Y146898D01*
G01X327100Y139857D02*
X326110Y138867D01*
G01D02*
G02X325827Y138750I-283J284D01*
G01D02*
X313598D01*
G01X329948Y178176D02*
X342458Y165833D01*
G01X318000Y866500D02*
X346000Y838500D01*
G01X318955Y867455D02*
X346955Y839455D01*
G01X327906Y970323D02*
Y873427D01*
G01D02*
G03X330199Y867891I7830J0D01*
G01X329256Y907239D02*
Y873428D01*
G01D02*
G03X331154Y868846I6480J0D01*
G01X316150Y985110D02*
Y870968D01*
G01D02*
G03X318000Y866500I6318J-1D01*
G01X317500Y898688D02*
Y870968D01*
G01D02*
G03X318955Y867455I4968J0D01*
G01X330196Y909119D02*
G02X329726Y908179I-1140J-18D01*
G01D02*
G03X329256Y907239I670J-922D01*
G01X317500Y923648D02*
Y903648D01*
G01D02*
G03X317970Y902708I1140J-18D01*
G01D02*
G02X318440Y901768I-670J-923D01*
G01D02*
Y900568D01*
G01D02*
G02X317970Y899628I-1140J-18D01*
G01D02*
G03X317500Y898688I670J-923D01*
G01X329256Y944519D02*
Y924519D01*
G01D02*
G03X329726Y923579I1140J-18D01*
G01D02*
G02X330196Y922639I-670J-922D01*
G01Y921439D02*
G02X329726Y920499I-1140J-18D01*
G01D02*
G03X329256Y919559I670J-922D01*
G01D02*
Y918359D01*
G01D02*
G03X329726Y917419I1140J-18D01*
G01D02*
G02X330196Y916479I-670J-922D01*
G01Y915279D02*
G02X329726Y914339I-1140J-18D01*
G01D02*
G03X329256Y913399I670J-922D01*
G01D02*
Y912199D01*
G01D02*
G03X329726Y911259I1140J-18D01*
G01D02*
G02X330196Y910319I-670J-922D01*
G01X318440Y926728D02*
Y925528D01*
G01D02*
G02X317970Y924588I-1140J-18D01*
G01D02*
G03X317500Y923648I670J-923D01*
G01Y960928D02*
Y940928D01*
G01D02*
G03X317970Y939988I1140J-18D01*
G01D02*
G02X318440Y939048I-670J-923D01*
G01D02*
Y937848D01*
G01D02*
G02X317970Y936908I-1140J-18D01*
G01D02*
G03X317500Y935968I670J-923D01*
G01D02*
Y934768D01*
G01D02*
G03X317970Y933828I1140J-18D01*
G01D02*
G02X318440Y932888I-670J-923D01*
G01D02*
Y931688D01*
G01D02*
G02X317970Y930748I-1140J-18D01*
G01D02*
G03X317500Y929808I670J-923D01*
G01D02*
Y928608D01*
G01D02*
G03X317970Y927668I1140J-18D01*
G01D02*
G02X318440Y926728I-670J-923D01*
G01X330196Y958719D02*
G02X329726Y957779I-1140J-18D01*
G01D02*
G03X329256Y956839I670J-922D01*
G01D02*
Y955639D01*
G01D02*
G03X329726Y954699I1140J-18D01*
G01D02*
G02X330196Y953759I-670J-922D01*
G01Y952559D02*
G02X329726Y951619I-1140J-18D01*
G01D02*
G03X329256Y950679I670J-922D01*
G01D02*
Y949479D01*
G01D02*
G03X329726Y948539I1140J-18D01*
G01D02*
G02X330196Y947599I-670J-922D01*
G01Y946399D02*
G02X329726Y945459I-1140J-18D01*
G01D02*
G03X329256Y944519I670J-922D01*
G01X331786Y980936D02*
G03X327906Y970323I12568J-10611D01*
G01X332819Y980065D02*
G03X329256Y970324I11535J-9741D01*
G01D02*
Y967959D01*
G01D02*
G03X329726Y967019I1140J-18D01*
G01D02*
G02X330196Y966079I-670J-922D01*
G01Y964879D02*
G02X329726Y963939I-1140J-18D01*
G01D02*
G03X329256Y962999I670J-922D01*
G01D02*
Y961799D01*
G01D02*
G03X329726Y960859I1140J-18D01*
G01D02*
G02X330196Y959919I-670J-922D01*
G01X318440Y976328D02*
Y975128D01*
G01D02*
G02X317970Y974188I-1140J-18D01*
G01D02*
G03X317500Y973248I670J-923D01*
G01D02*
Y972048D01*
G01D02*
G03X317970Y971108I1140J-18D01*
G01D02*
G02X318440Y970168I-670J-923D01*
G01D02*
Y968968D01*
G01D02*
G02X317970Y968028I-1140J-18D01*
G01D02*
G03X317500Y967088I670J-923D01*
G01D02*
Y965888D01*
G01D02*
G03X317970Y964948I1140J-18D01*
G01D02*
G02X318440Y964008I-670J-923D01*
G01D02*
Y962808D01*
G01D02*
G02X317970Y961868I-1140J-18D01*
G01D02*
G03X317500Y960928I670J-923D01*
G01X320228Y993600D02*
G02X318643Y989775I-5410J1D01*
G01D02*
X317684Y988816D01*
G01D02*
G03X316150Y985110I3705J-3704D01*
G01X321578Y993600D02*
G02X319598Y988820I-6760J0D01*
G01D02*
X318639Y987861D01*
G01D02*
G03X317500Y985111I2750J-2750D01*
G01D02*
Y978208D01*
G01D02*
G03X317970Y977268I1140J-18D01*
G01D02*
G02X318440Y976328I-670J-923D01*
G01X318813Y1009655D02*
Y1001066D01*
G01D02*
G03X319520Y999358I2417J0D01*
G01D02*
G02X320228Y997649I-1709J-1709D01*
G01D02*
Y993600D01*
G01X322993Y1009474D02*
Y1001416D01*
G01D02*
G02X322286Y999708I-2417J0D01*
G01D02*
G03X321578Y997999I1709J-1709D01*
G01D02*
Y993600D01*
G01X318898Y1009860D02*
G03X318813Y1009655I205J-205D01*
G01X322833Y1009860D02*
G02X322993Y1009474I-386J-386D01*
G01X334600Y129468D02*
X334544Y129524D01*
G01D02*
G03X332309Y130450I-2235J-2234D01*
G01X334600Y133031D02*
G02X331628Y131800I-2972J2972D01*
G01X331040Y152601D02*
Y152169D01*
G01D02*
G02X330271Y151400I-769J0D01*
G01X330929Y148600D02*
Y149250D01*
G01D02*
G03X330129Y150050I-800J0D01*
G01X353271Y150100D02*
X341000D01*
G01D02*
G02X338268Y151231I-1J3863D01*
G01X337313Y150276D02*
G03X341001Y148750I3685J3687D01*
G01D02*
X353272D01*
G01X337624Y159966D02*
G03X342501Y157947I4875J4876D01*
G01D02*
X367496D01*
G01X338579Y160921D02*
G03X342500Y159297I3921J3921D01*
G01D02*
X365915D01*
G01X342458Y165833D02*
X342580Y165711D01*
G01D02*
G03X345630Y164450I3047J3052D01*
G01D02*
X362302D01*
G01X330864Y179170D02*
X343407Y166795D01*
G01D02*
X343535Y166667D01*
G01D02*
G03X345629Y165800I2094J2095D01*
G01D02*
X362150D01*
G01X343000Y175000D02*
Y174987D01*
G01D02*
X349172Y168815D01*
G01X344350Y175560D02*
Y175547D01*
G01D02*
X349951Y169946D01*
G01X341650Y684337D02*
G03X345072Y676073I11685J-2D01*
G01D02*
X405600Y615545D01*
G01X343000Y684336D02*
G03X346027Y677028I10335J0D01*
G01D02*
X406555Y616500D01*
G01X334150Y825963D02*
Y679999D01*
G01D02*
G03X336627Y674018I8460J0D01*
G01D02*
X400021Y610624D01*
G01X335500Y825963D02*
Y680000D01*
G01D02*
G03X337582Y674973I7110J0D01*
G01D02*
X400976Y611579D01*
G01X341650Y828963D02*
Y684337D01*
G01X343000Y828963D02*
Y684336D01*
G01X332045Y831045D02*
G02X334150Y825963I-5082J-5082D01*
G01X333000Y832000D02*
G02X335500Y825963I-6037J-6036D01*
G01X346000Y838500D02*
G02X348650Y832102I-6398J-6398D01*
G01X339545Y834045D02*
G02X341650Y828963I-5082J-5082D01*
G01X340500Y835000D02*
G02X343000Y828963I-6037J-6036D01*
G01X330199Y867891D02*
X353364Y844726D01*
G01X331154Y868846D02*
X354319Y845681D01*
G01X343656Y952400D02*
Y866952D01*
G01D02*
G03X345500Y862500I6297J0D01*
G01D02*
X362500Y845500D01*
G01X345006Y890738D02*
Y875437D01*
G01D02*
G03X345476Y874497I1140J-18D01*
G01D02*
G02X345946Y873557I-670J-923D01*
G01D02*
Y872357D01*
G01D02*
G02X345476Y871417I-1140J-18D01*
G01D02*
G03X345006Y870477I670J-923D01*
G01D02*
Y866953D01*
G01D02*
G03X346455Y863455I4947J0D01*
G01X345476Y894758D02*
G02X345946Y893818I-670J-922D01*
G01D02*
Y892618D01*
G01D02*
G02X345476Y891678I-1140J-18D01*
G01D02*
G03X345006Y890738I670J-922D01*
G01Y928018D02*
Y908018D01*
G01D02*
G03X345476Y907078I1140J-18D01*
G01D02*
G02X345946Y906138I-670J-922D01*
G01D02*
Y904938D01*
G01D02*
G02X345476Y903998I-1140J-18D01*
G01D02*
G03X345006Y903058I670J-922D01*
G01D02*
Y901858D01*
G01D02*
G03X345476Y900918I1140J-18D01*
G01D02*
G02X345946Y899978I-670J-922D01*
G01D02*
Y898778D01*
G01D02*
G02X345476Y897838I-1140J-18D01*
G01D02*
G03X345006Y896898I670J-922D01*
G01D02*
Y895698D01*
G01D02*
G03X345476Y894758I1140J-18D01*
G01X330196Y910319D02*
Y909119D01*
G01Y922639D02*
Y921439D01*
G01Y916479D02*
Y915279D01*
G01X345946Y943418D02*
Y942218D01*
G01D02*
G02X345476Y941278I-1140J-18D01*
G01D02*
G03X345006Y940338I670J-922D01*
G01D02*
Y939138D01*
G01D02*
G03X345476Y938198I1140J-18D01*
G01D02*
G02X345946Y937258I-670J-922D01*
G01D02*
Y936058D01*
G01D02*
G02X345476Y935118I-1140J-18D01*
G01D02*
G03X345006Y934178I670J-922D01*
G01D02*
Y932978D01*
G01D02*
G03X345476Y932038I1140J-18D01*
G01D02*
G02X345946Y931098I-670J-922D01*
G01D02*
Y929898D01*
G01D02*
G02X345476Y928958I-1140J-18D01*
G01D02*
G03X345006Y928018I670J-922D01*
G01X347889Y962621D02*
G03X343656Y952400I10222J-10220D01*
G01X348844Y961666D02*
G03X345006Y952400I9266J-9266D01*
G01D02*
Y945298D01*
G01D02*
G03X345476Y944358I1140J-18D01*
G01D02*
G02X345946Y943418I-670J-922D01*
G01X330196Y959919D02*
Y958719D01*
G01Y953759D02*
Y952559D01*
G01Y947599D02*
Y946399D01*
G01Y966079D02*
Y964879D01*
G01X335938Y998898D02*
Y987019D01*
G01D02*
G02X334577Y983733I-4647J0D01*
G01D02*
X331786Y980942D01*
G01D02*
Y980936D01*
G01X337288Y999094D02*
Y987019D01*
G01D02*
G02X335532Y982778I-5997J-1D01*
G01D02*
X332819Y980065D01*
G01X334643Y1009860D02*
Y1002025D01*
G01D02*
G03X335290Y1000462I2211J0D01*
G01D02*
G02X335938Y998898I-1563J-1564D01*
G01X338583Y1009860D02*
Y1002220D01*
G01D02*
G02X337936Y1000658I-2209J0D01*
G01D02*
G03X337288Y999094I1563J-1564D01*
G01X364667Y155100D02*
X362755Y153188D01*
G01D02*
X361056D01*
G01D02*
X359918Y152050D01*
G01D02*
X356320D01*
G01D02*
G03X354904Y151464I-1J-2002D01*
G01D02*
X353731Y150291D01*
G01D02*
G02X353271Y150100I-461J460D01*
G01X353272Y148750D02*
G03X354687Y149336I0J2002D01*
G01D02*
X355859Y150508D01*
G01D02*
G02X356319Y150700I462J-459D01*
G01D02*
X360478D01*
G01D02*
X361616Y151838D01*
G01D02*
X362632D01*
G01D02*
X364311Y153517D01*
G01X362150Y165800D02*
G02X365158Y164554I0J-4254D01*
G01X349172Y168815D02*
G03X350132Y168570I960J1757D01*
G01D02*
X358663D01*
G01D02*
G02X359000Y168429I-2J-477D01*
G01D02*
X359394Y168035D01*
G01D02*
G03X360688Y167500I1292J1294D01*
G01D02*
X364329D01*
G01X349951Y169946D02*
G03X350132Y169920I182J625D01*
G01D02*
X358663D01*
G01D02*
G02X359955Y169385I0J-1828D01*
G01D02*
X360350Y168990D01*
G01D02*
G03X360688Y168850I338J338D01*
G01D02*
X364329D01*
G01X351677Y684178D02*
X410655Y625200D01*
G01X352632Y685133D02*
X411610Y626155D01*
G01X356150Y838000D02*
Y696130D01*
G01D02*
G03X359072Y689073I9978J-2D01*
G01D02*
X420600Y627545D01*
G01X357500Y838000D02*
Y696129D01*
G01D02*
G03X360027Y690028I8628J0D01*
G01D02*
X421555Y628500D01*
G01X348650Y832102D02*
Y691486D01*
G01D02*
G03X351677Y684178I10336J0D01*
G01X350000Y832102D02*
Y691487D01*
G01D02*
G03X352632Y685133I8986J0D01*
G01X353364Y844726D02*
G02X356150Y838000I-6726J-6726D01*
G01X354319Y845681D02*
G02X357500Y838000I-7681J-7680D01*
G01X346955Y839455D02*
G02X350000Y832102I-7353J-7352D01*
G01X357045Y862545D02*
X369045Y850545D01*
G01X358000Y863500D02*
X370000Y851500D01*
G01X362500Y845500D02*
G02X364650Y840309I-5191J-5191D01*
G01X346455Y863455D02*
X363455Y846455D01*
G01X353418Y950265D02*
Y869500D01*
G01D02*
X353417D01*
G01D02*
G03X355770Y863819I8034J0D01*
G01D02*
X357045Y862545D01*
G01X355708Y878281D02*
G02X355238Y877341I-1140J-18D01*
G01D02*
X354768Y876436D01*
G01D02*
Y875166D01*
G01D02*
X355238Y874261D01*
G01D02*
G02X355708Y873321I-670J-922D01*
G01D02*
Y872121D01*
G01D02*
G02X355238Y871181I-1140J-18D01*
G01D02*
X354768Y870276D01*
G01D02*
Y869500D01*
G01D02*
G03X356725Y864774I6683J-1D01*
G01D02*
X358000Y863500D01*
G01X354768Y901396D02*
Y881326D01*
G01D02*
X355238Y880421D01*
G01D02*
G02X355708Y879481I-670J-922D01*
G01D02*
Y878281D01*
G01Y910601D02*
Y909401D01*
G01D02*
G02X355238Y908461I-1140J-18D01*
G01D02*
X354768Y907556D01*
G01D02*
Y906286D01*
G01D02*
X355238Y905381D01*
G01D02*
G02X355708Y904441I-670J-922D01*
G01D02*
Y903241D01*
G01D02*
G02X355238Y902301I-1140J-18D01*
G01D02*
X354768Y901396D01*
G01Y942528D02*
Y924766D01*
G01D02*
X355238Y923861D01*
G01D02*
G02X355708Y922921I-670J-922D01*
G01D02*
Y921721D01*
G01D02*
G02X355238Y920781I-1140J-18D01*
G01D02*
X354768Y919876D01*
G01D02*
Y918606D01*
G01D02*
X355238Y917701D01*
G01D02*
G02X355708Y916761I-670J-922D01*
G01D02*
Y915561D01*
G01D02*
G02X355238Y914621I-1140J-18D01*
G01D02*
X354768Y913716D01*
G01D02*
Y912446D01*
G01D02*
X355238Y911541D01*
G01D02*
G02X355708Y910601I-670J-922D01*
G01X355238Y943468D02*
G03X354768Y942528I670J-922D01*
G01X379250Y979750D02*
X356000Y956500D01*
G01D02*
G03X353418Y950265I6235J-6234D01*
G01X371414Y970004D02*
X356955Y955545D01*
G01D02*
G03X354768Y950265I5280J-5280D01*
G01D02*
Y947488D01*
G01D02*
G03X355238Y946548I1140J-17D01*
G01D02*
G02X355708Y945608I-670J-922D01*
G01D02*
Y944408D01*
G01D02*
G02X355238Y943468I-1140J-17D01*
G01X351688Y999881D02*
Y970189D01*
G01D02*
G02X349023Y963755I-9099J0D01*
G01D02*
X347889Y962621D01*
G01X353038Y999814D02*
Y970190D01*
G01D02*
G02X349978Y962800I-10449J-2D01*
G01D02*
X348844Y961666D01*
G01X350393Y1009860D02*
Y1001794D01*
G01D02*
G03X350612Y1001267I746J1D01*
G01D02*
X350700Y1001179D01*
G01D02*
G03X351001Y1000977I653J648D01*
G01D02*
X351068Y1000949D01*
G01D02*
G02X351249Y1000829I-210J-514D01*
G01D02*
X351328Y1000750D01*
G01D02*
G02X351688Y999881I-869J-869D01*
G01X354333Y1009860D02*
Y1001110D01*
G01D02*
G02X353686Y1000462I-648J0D01*
G01D02*
G03X353038Y999814I0J-648D01*
G01X377520Y132067D02*
G03X378011Y132873I-1415J1415D01*
G01D02*
G03X378106Y133482I-1906J609D01*
G01D02*
Y134663D01*
G01D02*
X378181Y134738D01*
G01D02*
Y137704D01*
G01X378896Y131533D02*
G03X379181Y132221I-688J688D01*
G01X375756Y134882D02*
G03X376187Y135611I-1208J1206D01*
G01D02*
G03X376256Y136089I-1638J480D01*
G01D02*
Y136183D01*
G01D02*
G03X376213Y136564I-1742J-4D01*
G01D02*
G03X375968Y137141I-1700J-381D01*
G01D02*
G03X375745Y137416I-1458J-954D01*
G01D02*
X375165Y137995D01*
G01D02*
X375163Y137996D01*
G01D02*
X374872Y138289D01*
G01D02*
G02X374607Y138929I640J640D01*
G01X376656Y133872D02*
X376671Y133886D01*
G01X374607Y138929D02*
Y139383D01*
G01D02*
X374600Y139390D01*
G01X365140Y155100D02*
X364667D01*
G01X367496Y157947D02*
G03X368271Y158268I0J1096D01*
G01X365915Y159297D02*
G03X367129Y159800I0J1717D01*
G01D02*
X368041Y160712D01*
G01D02*
G03X368326Y161400I-688J688D01*
G01X364329Y167500D02*
G03X366737Y167988I1J6179D01*
G01D02*
G03X367318Y168270I-2404J5692D01*
G01D02*
G02X367844Y168196I214J-387D01*
G01D02*
X368334Y167706D01*
G01X364329Y168850D02*
G03X366211Y169232I0J4827D01*
G01D02*
G03X367743Y170264I-1882J4447D01*
G01D02*
X368309Y170830D01*
G01X364650Y702499D02*
G03X367127Y696518I8460J0D01*
G01D02*
X424100Y639545D01*
G01X368082Y697473D02*
X425055Y640500D01*
G01X372150Y843049D02*
Y709630D01*
G01D02*
G03X375072Y702573I9978J-2D01*
G01D02*
X431524Y646121D01*
G01X373500Y843050D02*
Y709629D01*
G01D02*
G03X376027Y703528I8628J0D01*
G01D02*
X432479Y647076D01*
G01X364650Y840309D02*
Y702499D01*
G01X366000Y840309D02*
Y702500D01*
G01D02*
G03X368082Y697473I7110J0D01*
G01X369045Y850545D02*
G02X372150Y843049I-7496J-7496D01*
G01X370000Y851500D02*
G02X373500Y843050I-8451J-8450D01*
G01X363455Y846455D02*
G02X366000Y840309I-6146J-6145D01*
G01X380499Y979089D02*
X374922Y973512D01*
G01D02*
G03X374589Y972515I793J-819D01*
G01D02*
G02X374257Y971518I-1126J-179D01*
G01D02*
X373408Y970669D01*
G01D02*
G02X372411Y970337I-818J794D01*
G01D02*
G03X371414Y970004I-178J-1126D01*
G01X383228Y994438D02*
G02X381954Y991363I-4348J0D01*
G01D02*
G03X380561Y988001I3363J-3363D01*
G01D02*
Y982500D01*
G01D02*
G02X379543Y980044I-3474J1D01*
G01D02*
X379250Y979750D01*
G01X384578Y994437D02*
G02X382909Y990408I-5698J0D01*
G01D02*
G03X381911Y988000I2408J-2409D01*
G01D02*
Y982499D01*
G01D02*
G02X380499Y979089I-4824J0D01*
G01X381888Y1009860D02*
Y1001477D01*
G01D02*
G03X382500Y1000000I2089J0D01*
G01D02*
G02X383228Y998242I-1758J-1758D01*
G01D02*
Y994438D01*
G01X385828Y1009860D02*
Y1002134D01*
G01D02*
G02X385203Y1000625I-2134J0D01*
G01D02*
G03X384578Y999116I1509J-1509D01*
G01D02*
Y994437D01*
G01X408848Y452020D02*
G03X410318Y448470I5020J-1D01*
G01D02*
X417466Y441322D01*
G01X410198Y452020D02*
G03X411273Y449425I3670J0D01*
G01D02*
X418421Y442277D01*
G01X402098Y450776D02*
G03X403396Y447642I4433J0D01*
G01D02*
X412566Y438472D01*
G01X403448Y450777D02*
G03X404351Y448597I3083J0D01*
G01D02*
X413520Y439428D01*
G01X408848Y607704D02*
Y452020D01*
G01X410198Y607705D02*
Y452020D01*
G01X402098Y605550D02*
Y450776D01*
G01X403448Y605581D02*
Y450777D01*
G01X405600Y615545D02*
G02X408848Y607704I-7841J-7841D01*
G01X406555Y616500D02*
G02X410198Y607705I-8796J-8795D01*
G01X400021Y610624D02*
G02X402097Y605611I-5013J-5013D01*
G01D02*
X402098Y605550D01*
G01X400976Y611579D02*
G02X403447Y605625I-5969J-5967D01*
G01D02*
X403448Y605581D01*
G01X410655Y625200D02*
G02X417205Y609387I-15813J-15813D01*
G01X411610Y626155D02*
G02X418555Y609388I-16768J-16767D01*
G01X395928Y733499D02*
G03X398460Y727385I8648J0D01*
G01D02*
X431190Y694655D01*
G01X397278Y733500D02*
G03X399416Y728340I7298J1D01*
G01D02*
X399877Y727878D01*
G01D02*
X432145Y695610D01*
G01X395928Y849500D02*
Y733499D01*
G01X397278Y783245D02*
Y733500D01*
G01Y795565D02*
Y794365D01*
G01D02*
G03X397748Y793425I1140J-18D01*
G01D02*
G02X398218Y792485I-670J-922D01*
G01D02*
Y791285D01*
G01D02*
G02X397748Y790345I-1140J-18D01*
G01D02*
G03X397278Y789405I670J-922D01*
G01D02*
Y788205D01*
G01D02*
G03X397748Y787265I1140J-18D01*
G01D02*
G02X398218Y786325I-670J-922D01*
G01D02*
Y785125D01*
G01D02*
G02X397748Y784185I-1140J-18D01*
G01D02*
G03X397278Y783245I670J-922D01*
G01Y812888D02*
Y800525D01*
G01D02*
G03X397748Y799585I1140J-18D01*
G01D02*
G02X398218Y798645I-670J-922D01*
G01D02*
Y797445D01*
G01D02*
G02X397748Y796505I-1140J-18D01*
G01D02*
G03X397278Y795565I670J-922D01*
G01X398218Y828288D02*
Y827088D01*
G01D02*
G02X397748Y826148I-1140J-18D01*
G01D02*
G03X397278Y825208I670J-922D01*
G01D02*
Y824008D01*
G01D02*
G03X397748Y823068I1140J-18D01*
G01D02*
G02X398218Y822128I-670J-922D01*
G01D02*
Y820928D01*
G01D02*
G02X397748Y819988I-1140J-18D01*
G01D02*
G03X397278Y819048I670J-922D01*
G01D02*
Y817848D01*
G01D02*
G03X397748Y816908I1140J-18D01*
G01D02*
G02X398218Y815968I-670J-922D01*
G01D02*
Y814768D01*
G01D02*
G02X397748Y813828I-1140J-18D01*
G01D02*
G03X397278Y812888I670J-922D01*
G01Y849500D02*
Y836328D01*
G01D02*
G03X397748Y835388I1140J-18D01*
G01D02*
G02X398218Y834448I-670J-922D01*
G01D02*
Y833248D01*
G01D02*
G02X397748Y832308I-1140J-18D01*
G01D02*
G03X397278Y831368I670J-922D01*
G01D02*
Y830168D01*
G01D02*
G03X397748Y829228I1140J-18D01*
G01D02*
G02X398218Y828288I-670J-922D01*
G01X404298Y869708D02*
G03X395928Y849500I20208J-20207D01*
G01X405253Y868753D02*
G03X397278Y849500I19253J-19253D01*
G01X433431Y898841D02*
X404298Y869708D01*
G01X434386Y897886D02*
X405253Y868753D01*
G01X425473Y436272D02*
Y416054D01*
G01D02*
G03X426156Y414403I2337J0D01*
G01D02*
X426157Y414402D01*
G01D02*
G02X426842Y412750I-1652J-1653D01*
G01D02*
Y408704D01*
G01D02*
G03X427450Y407235I2077J-1D01*
G01D02*
X428240Y406445D01*
G01D02*
G02X428533Y405896I-756J-756D01*
G01X426823Y436272D02*
Y416054D01*
G01D02*
G03X427112Y415358I986J2D01*
G01D02*
Y415357D01*
G01D02*
G02X428192Y412751I-2607J-2607D01*
G01D02*
Y409209D01*
G01D02*
G03X428542Y408859I350J0D01*
G01X421435Y426281D02*
Y411743D01*
G01D02*
G03X421686Y410482I3280J-3D01*
G01D02*
X421845Y410103D01*
G01D02*
G03X422227Y409534I1603J664D01*
G01D02*
X422231Y409530D01*
G01D02*
X422312Y409451D01*
G01D02*
G02X422723Y408835I-1343J-1341D01*
G01D02*
X423972Y406017D01*
G01D02*
G03X424424Y405359I1993J885D01*
G01D02*
G02X424605Y404922I-437J-437D01*
G01X422785Y426282D02*
Y411743D01*
G01D02*
G03X422933Y411002I1929J0D01*
G01D02*
X423011Y410814D01*
G01D02*
X423091Y410623D01*
G01D02*
X423093Y410620D01*
G01D02*
G03X423175Y410496I356J146D01*
G01D02*
G02X424605Y408859I-11412J-11412D01*
G01X418523Y425354D02*
Y408948D01*
G01D02*
G03X419255Y407180I2501J0D01*
G01D02*
X419761Y406674D01*
G01D02*
G02X420303Y405862I-1768J-1767D01*
G01D02*
X420668Y404981D01*
G01D02*
Y404922D01*
G01X419873Y425354D02*
Y410690D01*
G01D02*
G03X420605Y408922I2501J0D01*
G01D02*
X420668Y408859D01*
G01X428373Y446557D02*
Y423368D01*
G01D02*
G03X429500Y420645I3851J-1D01*
G01X418573Y438649D02*
Y433191D01*
G01D02*
G03X420105Y429491I5232J-1D01*
G01D02*
G02X421435Y426281I-3210J-3210D01*
G01X419923Y438648D02*
Y433191D01*
G01D02*
G03X421060Y430446I3882J0D01*
G01D02*
G02X422785Y426282I-4165J-4165D01*
G01X413705Y436160D02*
Y433025D01*
G01D02*
G03X414989Y429925I4385J0D01*
G01D02*
X414988Y429924D01*
G01D02*
X417791Y427122D01*
G01D02*
G02X418523Y425354I-1769J-1768D01*
G01X415055Y436160D02*
Y433026D01*
G01D02*
G03X415944Y430880I3035J0D01*
G01D02*
X418747Y428077D01*
G01D02*
G02X419873Y425354I-2726J-2721D01*
G01X424923Y452341D02*
G03X426235Y449171I4481J-2D01*
G01D02*
X426234Y449170D01*
G01D02*
X428035Y447370D01*
G01D02*
G02X428373Y446557I-812J-815D01*
G01X426273Y452340D02*
G03X427190Y450126I3131J0D01*
G01D02*
X428991Y448325D01*
G01X417204Y454200D02*
G03X420916Y445237I12674J-1D01*
G01D02*
X421406Y444749D01*
G01D02*
X422355Y443800D01*
G01D02*
G02X425473Y436272I-7528J-7528D01*
G01X418555Y454200D02*
G03X421871Y446193I11323J-1D01*
G01D02*
X422360Y445705D01*
G01D02*
X423310Y444755D01*
G01D02*
G02X426823Y436272I-8483J-8482D01*
G01X417466Y441322D02*
G02X418573Y438649I-2673J-2673D01*
G01X418421Y442277D02*
G02X419923Y438648I-3628J-3627D01*
G01X412566Y438472D02*
X412876Y438163D01*
G01D02*
G02X413705Y436160I-2003J-2002D01*
G01X413520Y439428D02*
X413831Y439119D01*
G01D02*
G02X415056Y436160I-2958J-2958D01*
G01D02*
X415055D01*
G01X424923Y617108D02*
Y452341D01*
G01X426273Y617107D02*
Y452340D01*
G01X417205Y609387D02*
Y454200D01*
G01D02*
X417204D01*
G01X418555Y609388D02*
Y454200D01*
G01X420600Y627545D02*
G02X424923Y617108I-10437J-10437D01*
G01X421555Y628500D02*
G02X426273Y617107I-11392J-11391D01*
G01X424100Y639545D02*
G02X431673Y621262I-18283J-18283D01*
G01X425055Y640500D02*
G02X433023Y621262I-19238J-19237D01*
G01X427878Y804520D02*
Y783959D01*
G01D02*
G03X429727Y779492I6323J1D01*
G01X425278Y808750D02*
G02X426971Y807322I-2024J-4117D01*
G01D02*
G02X427878Y804520I-3873J-2802D01*
G01X425278Y805250D02*
Y802000D01*
G01Y812250D02*
X425594Y812381D01*
G01D02*
G02X425825Y812427I231J-557D01*
G01D02*
G03X426303Y812625I0J676D01*
G01D02*
X427899Y814221D01*
G01D02*
G03X428133Y814786I-565J565D01*
G01D02*
Y816024D01*
G01D02*
G02X428367Y816589I799J0D01*
G01D02*
X434627Y822849D01*
G01X441255Y421514D02*
Y415586D01*
G01D02*
G03X441536Y414143I3850J1D01*
G01D02*
X441711Y413709D01*
G01D02*
X441887Y413274D01*
G01D02*
G02X441953Y412938I-829J-337D01*
G01D02*
Y408295D01*
G01D02*
G03X442685Y406527I2501J0D01*
G01D02*
X444290Y404922D01*
G01X442605Y421514D02*
Y415587D01*
G01D02*
G03X442788Y414649I2500J1D01*
G01D02*
X443139Y413781D01*
G01D02*
G02X443303Y412939I-2081J-842D01*
G01D02*
Y410205D01*
G01D02*
G03X443432Y409555I1696J-1D01*
G01D02*
X443572Y409218D01*
G01D02*
G03X443900Y408890I560J232D01*
G01D02*
G03X444054Y408859I154J369D01*
G01D02*
X444290D01*
G01X438478Y418909D02*
Y415854D01*
G01D02*
G02X438334Y415510I-487J2D01*
G01D02*
G03X437403Y413258I2254J-2250D01*
G01D02*
Y411591D01*
G01D02*
G03X437707Y410857I1038J0D01*
G01D02*
X438011Y410553D01*
G01D02*
G02X438036Y410524I-1881J-1647D01*
G01D02*
G02X438434Y409867I-1914J-1609D01*
G01D02*
G02X438623Y408915I-2312J-954D01*
G01D02*
Y408308D01*
G01D02*
G03X439355Y406540I2501J0D01*
G01D02*
X440134Y405761D01*
G01D02*
G02X440353Y405232I-529J-529D01*
G01D02*
Y404922D01*
G01X439828Y418909D02*
Y415854D01*
G01D02*
G02X439290Y414555I-1837J0D01*
G01D02*
G03X438753Y413258I1298J-1297D01*
G01D02*
Y412033D01*
G01D02*
G03X438917Y411639I558J1D01*
G01D02*
X439080Y411475D01*
G01D02*
X439603Y410952D01*
G01D02*
G02X440257Y409805I-1768J-1768D01*
G01D02*
X440312Y409591D01*
G01D02*
G02X440353Y409270I-1249J-323D01*
G01D02*
Y408859D01*
G01X433073Y418076D02*
G03X433303Y416764I3851J-1D01*
G01D02*
X434303Y414006D01*
G01D02*
X434304D01*
G01D02*
G02X434373Y413614I-1081J-392D01*
G01D02*
Y410160D01*
G01D02*
G03Y409871I2254J-145D01*
G01D02*
G03X434391Y409873I1J76D01*
G01D02*
X434373Y408458D01*
G01D02*
G03X435105Y406690I2501J0D01*
G01D02*
X436254Y405541D01*
G01D02*
G02X436416Y405151I-390J-391D01*
G01D02*
Y404922D01*
G01X434423Y418077D02*
G03X434573Y417225I2500J1D01*
G01D02*
X435573Y414467D01*
G01D02*
G02X435723Y413615I-2350J-853D01*
G01D02*
Y410160D01*
G01D02*
G03X435891Y409636I901J0D01*
G01D02*
X435940Y409567D01*
G01D02*
G03X436069Y409415I963J687D01*
G01D02*
X436341Y409143D01*
G01D02*
G02X436416Y408964I-178J-180D01*
G01D02*
Y408859D01*
G01X430223Y419446D02*
Y416284D01*
G01D02*
X430222D01*
G01D02*
G02X430095Y415494I-2499J-3D01*
G01D02*
X429601Y414013D01*
G01D02*
G03X429528Y413747I2371J-794D01*
G01D02*
X429457Y413416D01*
G01D02*
G03X429442Y413277I645J-140D01*
G01D02*
Y411522D01*
G01D02*
G03X429665Y410573I2131J0D01*
G01D02*
X429835Y410230D01*
G01D02*
G02X430242Y409248I-981J-982D01*
G01D02*
Y408539D01*
G01D02*
G03X430974Y406771I2501J0D01*
G01D02*
X432236Y405509D01*
G01D02*
G02X432479Y404922I-587J-587D01*
G01X431573Y419446D02*
Y416285D01*
G01D02*
G02X431376Y415067I-3850J-2D01*
G01D02*
X430882Y413585D01*
G01D02*
Y413584D01*
G01D02*
G03X430848Y413463I1088J-371D01*
G01D02*
X430801Y413243D01*
G01D02*
G03X430792Y413160I391J-84D01*
G01D02*
Y411899D01*
G01D02*
G03X431117Y410898I2488J255D01*
G01D02*
X431511Y410387D01*
G01D02*
X431568D01*
G01D02*
X432261Y409694D01*
G01D02*
G02X432479Y409168I-527J-527D01*
G01D02*
Y408859D01*
G01X428533Y405896D02*
G02X428542Y405809I-436J-89D01*
G01D02*
Y404922D01*
G01X439555Y435124D02*
Y425286D01*
G01D02*
G03X440682Y422563I3851J-1D01*
G01D02*
X440917Y422327D01*
G01D02*
G02X441255Y421514I-812J-815D01*
G01X440905Y435125D02*
Y425286D01*
G01D02*
G03X441637Y423518I2501J0D01*
G01D02*
X441873Y423282D01*
G01D02*
G02X442605Y421514I-1769J-1768D01*
G01X436385Y449642D02*
Y423074D01*
G01D02*
G03X437512Y420351I3851J-1D01*
G01D02*
X438141Y419722D01*
G01D02*
X438140D01*
G01D02*
G02X438478Y418909I-812J-815D01*
G01X437735Y449642D02*
Y423074D01*
G01D02*
G03X438467Y421306I2501J0D01*
G01D02*
X439096Y420677D01*
G01D02*
G02X439828Y418909I-1769J-1768D01*
G01X431673Y621262D02*
Y425852D01*
G01D02*
G03X432768Y423207I3740J-1D01*
G01D02*
G02X433073Y422472I-735J-736D01*
G01D02*
Y418076D01*
G01X433023Y621262D02*
Y425852D01*
G01D02*
G03X433723Y424162I2390J0D01*
G01D02*
G02X434423Y422472I-1690J-1690D01*
G01D02*
Y418077D01*
G01X429500Y420645D02*
X429885Y420259D01*
G01D02*
G02X430223Y419446I-812J-815D01*
G01X429723Y446557D02*
Y423368D01*
G01D02*
G03X430455Y421600I2501J0D01*
G01D02*
X430841Y421214D01*
G01D02*
G02X431573Y419446I-1769J-1768D01*
G01X446705Y452388D02*
G02X443355Y444300I-11438J0D01*
G01D02*
G03X439555Y435124I9174J-9174D01*
G01X448055Y452388D02*
G02X444310Y443345I-12788J-1D01*
G01D02*
G03X440905Y435125I8219J-8220D01*
G01X437709Y452545D02*
G03X436385Y449642I2521J-2903D01*
G01X438594Y451525D02*
G03X437735Y449642I1634J-1883D01*
G01X428991Y448325D02*
G02X429723Y446557I-1769J-1768D01*
G01X439705Y626370D02*
Y455401D01*
G01D02*
X439704Y455402D01*
G01D02*
G02X438972Y453634I-2501J0D01*
G01D02*
X438774Y453436D01*
G01D02*
G02X438652Y453330I-813J813D01*
G01D02*
X438471Y453194D01*
G01D02*
G03X438260Y453023I2318J-3075D01*
G01D02*
X437709Y452545D01*
G01X441055Y626370D02*
Y455402D01*
G01D02*
G02X439928Y452679I-3851J-1D01*
G01D02*
X439731Y452482D01*
G01D02*
G02X439463Y452249I-1770J1766D01*
G01D02*
X439281Y452113D01*
G01D02*
G03X439145Y452003I1503J-1998D01*
G01D02*
X438594Y451525D01*
G01X431524Y646121D02*
G02X439705Y626370I-19751J-19751D01*
G01X432479Y647076D02*
G02X441055Y626370I-20706J-20705D01*
G01X431190Y694655D02*
G02X446705Y657199I-37455J-37456D01*
G01X432145Y695610D02*
G02X448055Y657198I-38410J-38410D01*
G01X429802Y779416D02*
X449103Y760115D01*
G01X430763Y780365D02*
X450058Y761070D01*
G01X429727Y779492D02*
X429802Y779416D01*
G01X429228Y804470D02*
Y783960D01*
G01D02*
G03X430685Y780444I4973J1D01*
G01D02*
X430763Y780365D01*
G01X431778Y808750D02*
X430451Y807424D01*
G01D02*
G03X429227Y804470I2954J-2954D01*
G01D02*
X429228D01*
G01X440482Y815400D02*
Y803935D01*
G01D02*
G02X440248Y803370I-799J0D01*
G01D02*
X439212Y802334D01*
G01D02*
G02X438647Y802100I-565J565D01*
G01D02*
X438278D01*
G01X441832Y815400D02*
Y805077D01*
G01D02*
G03X442066Y804512I799J0D01*
G01D02*
X444266Y802312D01*
G01D02*
G03X444778Y802100I512J512D01*
G01X431778Y805250D02*
Y802000D01*
G01X434627Y822849D02*
X435306Y823530D01*
G01D02*
G02X438260Y824753I2953J-2953D01*
G01D02*
Y824752D01*
G01D02*
G03X438721Y824943I0J652D01*
G01D02*
X447522Y833744D01*
G01X431778Y812250D02*
X431059D01*
G01D02*
G02X430494Y812484I0J799D01*
G01D02*
X429717Y813261D01*
G01D02*
G02X429483Y813826I565J565D01*
G01D02*
Y815464D01*
G01D02*
G02X429717Y816029I799J0D01*
G01D02*
X435583Y821895D01*
G01D02*
X436262Y822575D01*
G01D02*
G02X438260Y823402I1997J-1998D01*
G01D02*
G03X439676Y823988I1J2002D01*
G01D02*
X448477Y832789D01*
G01X446466Y824189D02*
X444227Y821950D01*
G01D02*
X442464Y820188D01*
G01D02*
G03X440481Y815400I4788J-4788D01*
G01D02*
X440482D01*
G01X445182Y820995D02*
X443419Y819233D01*
G01D02*
G03X441832Y815400I3833J-3832D01*
G01X433828Y878297D02*
G02X432509Y876093I-2500J-1D01*
G01D02*
X432186Y875920D01*
G01D02*
G02X431511Y875750I-676J1259D01*
G01D02*
X431278D01*
G01X435307Y877838D02*
X435446Y877501D01*
G01D02*
G03X436298Y876461I2145J888D01*
G01D02*
X436475Y876342D01*
G01D02*
G03X436913Y876108I1391J2077D01*
G01D02*
X437778Y875750D01*
G01X431278Y872250D02*
X431853D01*
G01D02*
G02X432835Y871843I0J-1388D01*
G01D02*
X433451Y871227D01*
G01D02*
G02X433667Y870951I-1021J-1021D01*
G01D02*
G02X433748Y870767I-690J-413D01*
G01D02*
G03X433784Y870692I266J82D01*
G01D02*
X433807Y870657D01*
G01D02*
G02X433880Y870520I-666J-443D01*
G01D02*
X434067Y870068D01*
G01D02*
G02X434119Y869873I-740J-302D01*
G01D02*
G02X434127Y869762I-791J-113D01*
G01D02*
X434128D01*
G01D02*
Y868631D01*
G01D02*
G03X434758Y867111I2149J0D01*
G01D02*
X435264Y866605D01*
G01D02*
X436782Y865086D01*
G01D02*
G03X438198Y864500I1415J1416D01*
G01D02*
X443009D01*
G01D02*
G02X443469Y864309I-1J-651D01*
G01D02*
X446841Y860937D01*
G01X437778Y872250D02*
X437303D01*
G01D02*
G03X437014Y872193I-1J-755D01*
G01D02*
X435844Y871708D01*
G01D02*
G03X435528Y871426I247J-595D01*
G01D02*
G03X435478Y871234I344J-192D01*
G01D02*
Y868632D01*
G01D02*
X435479Y868631D01*
G01D02*
G03X435713Y868066I799J0D01*
G01D02*
X436725Y867053D01*
G01D02*
X437737Y866041D01*
G01D02*
G03X438198Y865850I461J461D01*
G01D02*
X443009D01*
G01D02*
G02X444424Y865264I0J-2001D01*
G01D02*
X447796Y861892D01*
G01X448024Y901056D02*
X437522Y890555D01*
G01D02*
X435354Y888387D01*
G01D02*
G03X433828Y884700I3688J-3686D01*
G01D02*
Y878297D01*
G01X453976Y905098D02*
X436978Y888100D01*
G01D02*
X436309Y887432D01*
G01D02*
G03X435178Y884700I2732J-2731D01*
G01D02*
Y878485D01*
G01D02*
G03X435307Y877838I1693J1D01*
G01X445312Y882766D02*
G03X444747Y883000I-565J-565D01*
G01D02*
X444278D01*
G01X431278D02*
Y879250D01*
G01X437778Y883000D02*
Y879250D01*
G01X438650Y911440D02*
G02X433431Y898841I-17817J0D01*
G01X440000Y911439D02*
G02X434386Y897886I-19167J0D01*
G01X438650Y999062D02*
Y911440D01*
G01X440000Y1000166D02*
Y911439D01*
G01X437008Y1009860D02*
Y1003026D01*
G01D02*
G03X438184Y1000187I4015J0D01*
G01D02*
G02X438650Y999062I-1125J-1125D01*
G01X440943Y1009860D02*
Y1001109D01*
G01D02*
G02X440297Y1000463I-646J0D01*
G01D02*
X440000Y1000166D01*
G01X455635Y428221D02*
Y417581D01*
G01D02*
G02X455298Y416768I-1151J1D01*
G01D02*
X454040Y415510D01*
G01D02*
G03X452922Y412812I2696J-2698D01*
G01D02*
G03X454039Y410116I3813J1D01*
G01D02*
X454331Y409824D01*
G01D02*
G02X454623Y409119I-705J-705D01*
G01D02*
Y408428D01*
G01D02*
G03X455355Y406660I2501J0D01*
G01D02*
X455580Y406435D01*
G01D02*
G02X456223Y404883I-1552J-1552D01*
G01X456985Y428220D02*
Y417581D01*
G01D02*
G02X456253Y415813I-2501J0D01*
G01D02*
X454995Y414555D01*
G01D02*
G03X454273Y412812I1742J-1743D01*
G01D02*
G03X454994Y411071I2463J0D01*
G01D02*
X455286Y410779D01*
G01D02*
G02X455578Y410487I-1514J-1806D01*
G01D02*
X455548Y410467D01*
G01D02*
X455849Y410216D01*
G01D02*
G02X456223Y409312I-904J-903D01*
G01D02*
Y408783D01*
G01X449173Y419372D02*
Y415998D01*
G01D02*
G03X449427Y414794I2965J-3D01*
G01D02*
G03X449527Y414591I2708J1208D01*
G01D02*
G02X449761Y414120I-1683J-1130D01*
G01D02*
G02X449834Y413858I-2167J-745D01*
G01D02*
G02X449873Y413460I-1988J-396D01*
G01D02*
Y409738D01*
G01D02*
G03X451644Y405461I6048J-1D01*
G01D02*
X452223Y404883D01*
G01X450523Y419372D02*
Y415998D01*
G01D02*
G03X450694Y415275I1614J0D01*
G01D02*
G02X451039Y414560I-2849J-1815D01*
G01D02*
G02X451157Y414123I-3195J-1097D01*
G01D02*
G02X451223Y413460I-3312J-664D01*
G01D02*
Y411197D01*
G01D02*
G03X452223Y408783I3414J0D01*
G01X446023Y435400D02*
Y416440D01*
G01D02*
G02X445703Y415198I-2570J0D01*
G01D02*
G03X445645Y415096I3319J-1955D01*
G01D02*
G03X445173Y413247I3380J-1847D01*
G01D02*
Y411868D01*
G01D02*
G03X445954Y409542I3851J-1D01*
G01D02*
G02X446411Y408555I-837J-987D01*
G01D02*
G03X446472Y408305I2456J467D01*
G01D02*
G03X446691Y407789I2397J713D01*
G01D02*
X447549Y406271D01*
G01D02*
G02X447681Y406001I-2176J-1231D01*
G01D02*
X448059Y405090D01*
G01D02*
X448227Y404922D01*
G01X447373Y435400D02*
Y416440D01*
G01D02*
G02X446885Y414545I-3920J-1D01*
G01D02*
G02X446830Y414448I-4232J2335D01*
G01D02*
G03X446523Y413247I2194J-1201D01*
G01D02*
Y411867D01*
G01D02*
X446524Y411868D01*
G01D02*
G03X447030Y410357I2501J-3D01*
G01D02*
X447031D01*
G01D02*
G03X447254Y410102I1990J1515D01*
G01D02*
X447582Y409774D01*
G01D02*
X447586Y409764D01*
G01D02*
G02X447746Y409571I-929J-933D01*
G01D02*
X448227Y408859D01*
G01X466830Y442445D02*
X457776Y433391D01*
G01D02*
G03X455635Y428221I5172J-5170D01*
G01X467785Y441490D02*
X459635Y433340D01*
G01D02*
X458732Y432436D01*
G01D02*
G03X456985Y428220I4216J-4217D01*
G01X452705Y435311D02*
Y425770D01*
G01D02*
G02X451808Y423604I-3063J0D01*
G01D02*
X450299Y422095D01*
G01D02*
G03X449173Y419372I2726J-2721D01*
G01X454055Y435311D02*
Y425770D01*
G01D02*
G02X452763Y422649I-4413J-1D01*
G01D02*
X452185Y422070D01*
G01D02*
X451255Y421140D01*
G01D02*
G03X450523Y419372I1769J-1768D01*
G01X461877Y449447D02*
X456215Y443785D01*
G01D02*
G03X452705Y435311I8474J-8474D01*
G01X462832Y448492D02*
X457170Y442830D01*
G01D02*
G03X454055Y435311I7519J-7520D01*
G01X453500Y749500D02*
Y448327D01*
G01D02*
G02X452965Y447035I-1827J0D01*
G01D02*
X451992Y446062D01*
G01D02*
X449340Y443411D01*
G01D02*
G03X446022Y435400I8011J-8011D01*
G01D02*
X446023D01*
G01X454850Y582485D02*
Y448327D01*
G01D02*
G02X453920Y446080I-3177J-1D01*
G01D02*
X452947Y445107D01*
G01D02*
X450295Y442456D01*
G01D02*
G03X447373Y435400I7056J-7055D01*
G01X446705Y657199D02*
Y452388D01*
G01X448055Y657198D02*
Y452388D01*
G01X454850Y670563D02*
Y587445D01*
G01D02*
G03X455320Y586505I1140J-18D01*
G01D02*
G02X455790Y585565I-670J-922D01*
G01D02*
Y584365D01*
G01D02*
G02X455320Y583425I-1140J-18D01*
G01D02*
G03X454850Y582485I670J-922D01*
G01X455320Y680743D02*
G02X455790Y679803I-670J-922D01*
G01D02*
Y678603D01*
G01D02*
G02X455320Y677663I-1140J-18D01*
G01D02*
G03X454850Y676723I670J-922D01*
G01D02*
Y675523D01*
G01D02*
G03X455320Y674583I1140J-18D01*
G01D02*
G02X455790Y673643I-670J-922D01*
G01D02*
Y672443D01*
G01D02*
G02X455320Y671503I-1140J-18D01*
G01D02*
G03X454850Y670563I670J-922D01*
G01Y721943D02*
Y687843D01*
G01D02*
G03X455320Y686903I1140J-18D01*
G01D02*
G02X455790Y685963I-670J-922D01*
G01D02*
Y684763D01*
G01D02*
G02X455320Y683823I-1140J-18D01*
G01D02*
G03X454850Y682883I670J-922D01*
G01D02*
Y681683D01*
G01D02*
G03X455320Y680743I1140J-18D01*
G01X455790Y729983D02*
G02X455320Y729043I-1140J-18D01*
G01D02*
G03X454850Y728103I670J-922D01*
G01D02*
Y726903D01*
G01D02*
G03X455320Y725963I1140J-18D01*
G01D02*
G02X455790Y725023I-670J-922D01*
G01D02*
Y723823D01*
G01D02*
G02X455320Y722883I-1140J-18D01*
G01D02*
G03X454850Y721943I670J-922D01*
G01Y749501D02*
Y739223D01*
G01D02*
G03X455320Y738283I1140J-18D01*
G01D02*
G02X455790Y737343I-670J-922D01*
G01D02*
Y736143D01*
G01D02*
G02X455320Y735203I-1140J-18D01*
G01D02*
G03X454850Y734263I670J-922D01*
G01D02*
Y733063D01*
G01D02*
G03X455320Y732123I1140J-18D01*
G01D02*
G02X455790Y731183I-670J-922D01*
G01D02*
Y729983D01*
G01X449103Y760115D02*
G02X453500Y749500I-10615J-10615D01*
G01X450058Y761070D02*
G02X454850Y749501I-11570J-11569D01*
G01X458828Y780181D02*
G03X461148Y774580I7922J0D01*
G01D02*
X461220Y774508D01*
G01D02*
G02X462673Y771000I-3508J-3508D01*
G01X460178Y780182D02*
G03X462103Y775535I6572J0D01*
G01X458828Y805706D02*
Y780181D01*
G01X460178Y805100D02*
Y780182D01*
G01X456278Y808750D02*
G02X457729Y808149I0J-2052D01*
G01D02*
X457878Y808000D01*
G01D02*
G02X458703Y806595I-2295J-2292D01*
G01D02*
G02X458715Y806549I-3132J-842D01*
G01D02*
G02X458828Y805706I-3130J-849D01*
G01X462778Y808750D02*
G03X460577Y807500I0J-2563D01*
G01D02*
G03X460429Y807013I7019J-2399D01*
G01D02*
G03X460178Y805100I7167J-1913D01*
G01X456278Y805250D02*
Y802100D01*
G01Y812250D02*
X457900D01*
G01D02*
G03X458700Y813050I0J800D01*
G01D02*
Y816493D01*
G01D02*
G02X459200Y817700I1707J0D01*
G01D02*
G03X459524Y818482I-782J782D01*
G01D02*
Y836028D01*
G01X461581Y812250D02*
G02X460050Y813781I0J1531D01*
G01D02*
Y816492D01*
G01D02*
G02X460155Y816745I357J0D01*
G01D02*
G03X460874Y818481I-1737J1736D01*
G01D02*
Y836027D01*
G01X451459Y829181D02*
X446466Y824189D01*
G01X452414Y828226D02*
X445183Y820995D01*
G01D02*
X445182D01*
G01X459524Y836028D02*
G03X459397Y836334I-432J0D01*
G01D02*
X459342Y836389D01*
G01D02*
G02X459215Y836695I305J306D01*
G01D02*
Y839000D01*
G01X460874Y836027D02*
G02X461001Y836334I435J0D01*
G01D02*
X461057Y836390D01*
G01D02*
G03X461184Y836697I-308J307D01*
G01D02*
Y839000D01*
G01X447522Y833744D02*
G03X447713Y834205I-461J461D01*
G01D02*
Y836029D01*
G01D02*
G03X447586Y836335I-432J0D01*
G01D02*
X447531Y836390D01*
G01D02*
G02X447404Y836696I305J306D01*
G01D02*
Y839000D01*
G01X448477Y832789D02*
G03X449063Y834205I-1416J1415D01*
G01D02*
Y836029D01*
G01D02*
G02X449190Y836335I432J0D01*
G01D02*
X449245Y836390D01*
G01D02*
G03X449372Y836696I-305J306D01*
G01D02*
Y839000D01*
G01X451341D02*
Y836696D01*
G01D02*
G03X451468Y836390I432J0D01*
G01D02*
X451523Y836335D01*
G01D02*
G02X451650Y836029I-305J-306D01*
G01D02*
Y829641D01*
G01D02*
G02X451459Y829181I-651J1D01*
G01X453309Y839000D02*
Y836696D01*
G01D02*
G02X453182Y836390I-432J0D01*
G01D02*
X453127Y836335D01*
G01D02*
G03X453000Y836029I305J-306D01*
G01D02*
Y829640D01*
G01D02*
G02X452414Y828226I-2001J1D01*
G01X460856Y863217D02*
G03X459524Y860001I3219J-3217D01*
G01D02*
Y855972D01*
G01D02*
G02X459397Y855666I-432J0D01*
G01D02*
X459342Y855611D01*
G01D02*
G03X459215Y855305I305J-306D01*
G01D02*
Y853000D01*
G01X461812Y862263D02*
G03X460874Y860000I2263J-2264D01*
G01D02*
Y855973D01*
G01D02*
G03X461001Y855666I435J0D01*
G01D02*
X461057Y855610D01*
G01D02*
G02X461184Y855303I-308J-307D01*
G01D02*
Y853000D01*
G01X446841Y860937D02*
G02X447718Y858820I-2117J-2117D01*
G01D02*
Y855442D01*
G01D02*
G02X447561Y855063I-536J0D01*
G01D02*
G03X447404Y854684I379J-379D01*
G01D02*
Y853000D01*
G01X447796Y861892D02*
G02X449068Y858821I-3072J-3071D01*
G01D02*
Y855395D01*
G01D02*
G03X449220Y855028I519J0D01*
G01D02*
G02X449372Y854661I-367J-367D01*
G01D02*
Y853000D01*
G01X451341D02*
Y855304D01*
G01D02*
G02X451468Y855610I432J0D01*
G01D02*
X451523Y855665D01*
G01D02*
G03X451650Y855971I-305J306D01*
G01D02*
Y861195D01*
G01X453309Y853000D02*
Y855304D01*
G01D02*
G03X453182Y855610I-432J0D01*
G01D02*
X453127Y855665D01*
G01D02*
G02X453000Y855971I305J306D01*
G01D02*
Y861196D01*
G01X462237Y876252D02*
X461077Y875772D01*
G01D02*
G02X460964Y875750I-112J274D01*
G01D02*
X460778D01*
G01Y872250D02*
X461597D01*
G01X462458Y864820D02*
X461056Y863418D01*
G01D02*
X460856Y863217D01*
G01X451650Y861195D02*
G03X450573Y863795I-3677J0D01*
G01D02*
X448377Y865991D01*
G01D02*
G02X446928Y869499I3522J3508D01*
G01D02*
Y880819D01*
G01X453000Y861196D02*
G03X451528Y864750I-5027J0D01*
G01D02*
X449333Y866945D01*
G01D02*
G02X448278Y869500I2566J2555D01*
G01D02*
Y880919D01*
G01X446928Y880819D02*
G03X446694Y881384I-799J0D01*
G01D02*
X445312Y882766D01*
G01X448278Y880919D02*
X448276D01*
G01D02*
X448278Y881019D01*
G01D02*
X448276D01*
G01D02*
X448278Y881069D01*
G01D02*
G02X448512Y881634I799J0D01*
G01D02*
X449644Y882766D01*
G01D02*
G02X450209Y883000I565J-565D01*
G01D02*
X450778D01*
G01X460778Y879250D02*
Y883000D01*
G01X453828Y998493D02*
Y908000D01*
G01D02*
G02X453021Y906053I-2754J1D01*
G01D02*
X448024Y901056D01*
G01X455178Y998564D02*
Y908000D01*
G01D02*
G02X453976Y905098I-4104J0D01*
G01X452758Y1009860D02*
Y1001077D01*
G01D02*
G03X453293Y999785I1828J0D01*
G01D02*
G02X453828Y998493I-1293J-1292D01*
G01X456693Y1009860D02*
Y1002151D01*
G01D02*
G02X455961Y1000383I-2501J0D01*
G01D02*
X455910Y1000332D01*
G01D02*
G03X455178Y998564I1769J-1768D01*
G01X464964Y418438D02*
Y412657D01*
G01D02*
G03X465767Y410302I3852J-1D01*
G01D02*
G02X466091Y409580I-642J-722D01*
G01D02*
Y408530D01*
G01D02*
G03X466823Y406762I2501J0D01*
G01D02*
X467384Y406201D01*
G01D02*
G02X467914Y404922I-1278J-1279D01*
G01X466314Y418438D02*
Y412657D01*
G01D02*
G03X466835Y411127I2502J-2D01*
G01D02*
G03X467046Y410889I1974J1537D01*
G01D02*
X467182Y410753D01*
G01D02*
G02X467292Y410634I-1780J-1756D01*
G01D02*
G02X467914Y408985I-1879J-1650D01*
G01D02*
Y408859D01*
G01X462186Y431061D02*
Y409924D01*
G01D02*
G03Y409300I2857J-312D01*
G01D02*
Y408038D01*
G01D02*
G03X462392Y407131I2100J0D01*
G01D02*
X462787Y406307D01*
G01D02*
G03X463005Y406000I1009J485D01*
G01D02*
G02X463172Y405816I-1766J-1770D01*
G01D02*
X463522Y405388D01*
G01D02*
X463547Y405358D01*
G01D02*
G03X463600Y405299I619J503D01*
G01D02*
X463977Y404922D01*
G01X463536Y431060D02*
Y409924D01*
G01D02*
G03X463977Y408859I1506J0D01*
G01X480642Y438612D02*
X470073Y428043D01*
G01D02*
X469722Y427694D01*
G01D02*
G03X468572Y424916I2777J-2777D01*
G01D02*
G02X467672Y422742I-3076J0D01*
G01D02*
X466090Y421161D01*
G01D02*
G03X464964Y418438I2726J-2721D01*
G01X481597Y437657D02*
X471027Y427087D01*
G01D02*
X470677Y426738D01*
G01D02*
G03X469923Y424916I1822J-1821D01*
G01D02*
G02X468627Y421787I-4426J0D01*
G01D02*
X467046Y420206D01*
G01D02*
G03X466314Y418438I1769J-1768D01*
G01X474559Y445029D02*
X463313Y433782D01*
G01D02*
G03X462186Y431061I2723J-2722D01*
G01X475514Y444074D02*
X464268Y432827D01*
G01D02*
G03X463536Y431060I1768J-1768D01*
G01X476705Y612382D02*
Y450210D01*
G01D02*
G02X474559Y445029I-7327J0D01*
G01X478055Y450211D02*
G02X475514Y444074I-8677J-2D01*
G01X469705Y619521D02*
Y449386D01*
G01D02*
G02X466830Y442445I-9816J0D01*
G01X471055Y619520D02*
Y449386D01*
G01D02*
G02X467785Y441490I-11166J-1D01*
G01X462673Y451369D02*
G02X461877Y449447I-2718J0D01*
G01X464023Y451370D02*
G02X462832Y448492I-4068J-2D01*
G01X462673Y771000D02*
Y451369D01*
G01X464023Y679303D02*
Y451370D01*
G01X483900Y629755D02*
G03X476705Y612382I17372J-17371D01*
G01X476450Y635805D02*
G03X469705Y619521I16285J-16284D01*
G01X477405Y634850D02*
G03X471055Y619520I15330J-15330D01*
G01X512572Y671927D02*
X476450Y635805D01*
G01X513527Y670972D02*
X477405Y634850D01*
G01X464963Y681183D02*
G02X464493Y680243I-1140J-18D01*
G01D02*
G03X464023Y679303I670J-922D01*
G01Y715927D02*
Y696583D01*
G01D02*
G03X464493Y695643I1140J-18D01*
G01D02*
G02X464963Y694703I-670J-922D01*
G01D02*
Y693503D01*
G01D02*
G02X464493Y692563I-1140J-18D01*
G01D02*
G03X464023Y691623I670J-922D01*
G01D02*
Y690423D01*
G01D02*
G03X464493Y689483I1140J-18D01*
G01D02*
G02X464963Y688543I-670J-922D01*
G01D02*
Y687343D01*
G01D02*
G02X464493Y686403I-1140J-18D01*
G01D02*
G03X464023Y685463I670J-922D01*
G01D02*
Y684263D01*
G01D02*
G03X464493Y683323I1140J-18D01*
G01D02*
G02X464963Y682383I-670J-922D01*
G01D02*
Y681183D01*
G01Y730127D02*
G02X464493Y729187I-1140J-18D01*
G01D02*
G03X464023Y728247I670J-922D01*
G01D02*
Y727047D01*
G01D02*
G03X464493Y726107I1140J-18D01*
G01D02*
G02X464963Y725167I-670J-922D01*
G01D02*
Y723967D01*
G01D02*
G02X464493Y723027I-1140J-18D01*
G01D02*
G03X464023Y722087I670J-922D01*
G01D02*
Y720887D01*
G01D02*
G03X464493Y719947I1140J-18D01*
G01D02*
G02X464963Y719007I-670J-922D01*
G01D02*
Y717807D01*
G01D02*
G02X464493Y716867I-1140J-18D01*
G01D02*
G03X464023Y715927I670J-922D01*
G01Y771000D02*
Y739367D01*
G01D02*
G03X464493Y738427I1140J-18D01*
G01D02*
G02X464963Y737487I-670J-922D01*
G01D02*
Y736287D01*
G01D02*
G02X464493Y735347I-1140J-18D01*
G01D02*
G03X464023Y734407I670J-922D01*
G01D02*
Y733207D01*
G01D02*
G03X464493Y732267I1140J-18D01*
G01D02*
G02X464963Y731327I-670J-922D01*
G01D02*
Y730127D01*
G01X462103Y775535D02*
X462175Y775463D01*
G01D02*
G02X464023Y771000I-4463J-4462D01*
G01X471778Y825381D02*
Y804431D01*
G01D02*
G02X471544Y803866I-799J0D01*
G01D02*
X470012Y802334D01*
G01D02*
G02X469447Y802100I-565J565D01*
G01D02*
X469278D01*
G01X473128Y825382D02*
Y804681D01*
G01D02*
G03X473362Y804116I799J0D01*
G01D02*
X475144Y802334D01*
G01D02*
G03X475709Y802100I565J565D01*
G01D02*
X475778D01*
G01X462778Y805250D02*
Y802100D01*
G01Y812250D02*
X461581D01*
G01X464252Y834116D02*
X470923Y827445D01*
G01D02*
G02X471778Y825381I-2064J-2064D01*
G01X471878Y828400D02*
G02X473128Y825382I-3019J-3018D01*
G01X463152Y839000D02*
Y836695D01*
G01D02*
G03X463279Y836389I432J0D01*
G01D02*
X463334Y836334D01*
G01D02*
G02X463461Y836028I-305J-306D01*
G01D02*
Y836027D01*
G01D02*
G03X464252Y834116I2702J-1D01*
G01X465121Y839000D02*
Y836697D01*
G01D02*
G02X464994Y836390I-435J0D01*
G01D02*
X464938Y836334D01*
G01D02*
G03X464811Y836027I308J-307D01*
G01D02*
G03X465207Y835071I1352J0D01*
G01D02*
X471878Y828400D01*
G01X463152Y853000D02*
Y853082D01*
G01D02*
X463428Y853358D01*
G01D02*
Y857299D01*
G01D02*
G02X464735Y860457I4464J2D01*
G01D02*
X465478Y861200D01*
G01X465121Y853000D02*
X464922Y853199D01*
G01D02*
G02X464778Y853546I346J347D01*
G01D02*
Y857300D01*
G01D02*
G02X465690Y859502I3114J0D01*
G01D02*
X475805Y869617D01*
G01X463162Y877680D02*
X462805Y876820D01*
G01D02*
G02X462577Y876479I-974J404D01*
G01D02*
G02X462237Y876252I-741J741D01*
G01X464846Y877684D02*
X465133Y876990D01*
G01D02*
G03X465468Y876490I1426J593D01*
G01D02*
G03X465969Y876156I1090J1092D01*
G01D02*
X466875Y875780D01*
G01D02*
G03X467027Y875750I152J368D01*
G01D02*
X467278D01*
G01X461597Y872250D02*
G02X462162Y872016I0J-799D01*
G01D02*
X462801Y871377D01*
G01D02*
G02X463035Y870812I-565J-565D01*
G01D02*
Y866211D01*
G01D02*
X463034Y866212D01*
G01D02*
G02X462458Y864820I-1968J-1D01*
G01X467278Y872250D02*
X466859D01*
G01D02*
G03X466294Y872016I0J-799D01*
G01D02*
X464619Y870341D01*
G01D02*
G03X464385Y869776I565J-565D01*
G01D02*
Y866212D01*
G01D02*
G02X463413Y863865I-3319J0D01*
G01D02*
X462013Y862465D01*
G01D02*
X461812Y862263D01*
G01X465478Y861200D02*
X465477D01*
G01D02*
X474299Y870022D01*
G01D02*
X474582Y870304D01*
G01D02*
X474850Y870572D01*
G01D02*
G03X476278Y874019I-3446J3447D01*
G01D02*
Y881069D01*
G01X475805Y869617D02*
G03X477628Y874018I-4401J4401D01*
G01D02*
Y880719D01*
G01X468023Y895655D02*
X465137Y892769D01*
G01D02*
G03X463328Y888400I4370J-4368D01*
G01D02*
Y878511D01*
G01D02*
G02X463162Y877680I-2169J1D01*
G01X468978Y894700D02*
X466092Y891814D01*
G01D02*
G03X464678Y888400I3414J-3414D01*
G01D02*
Y878529D01*
G01D02*
G03X464846Y877684I2209J0D01*
G01X476278Y881069D02*
G03X476044Y881634I-799J0D01*
G01D02*
X474912Y882766D01*
G01D02*
G03X474347Y883000I-565J-565D01*
G01D02*
X473778D01*
G01X477628Y880719D02*
G02X477862Y881284I799J0D01*
G01X467278Y879250D02*
Y883000D01*
G01X469828Y998913D02*
Y900013D01*
G01D02*
G02X468023Y895655I-6163J0D01*
G01X471178Y998606D02*
Y900013D01*
G01D02*
G02X468978Y894700I-7513J-1D01*
G01X468503Y1009860D02*
Y1002111D01*
G01D02*
G03X469164Y1000513I2262J0D01*
G01D02*
X469165Y1000512D01*
G01D02*
G02X469828Y998913I-1599J-1600D01*
G01X472443Y1009860D02*
Y1001659D01*
G01D02*
G02X471810Y1000132I-2158J0D01*
G01D02*
G03X471178Y998606I1526J-1526D01*
G01X484000Y322000D02*
Y318709D01*
G01D02*
G02X483955Y318600I-154J0D01*
G01X486555Y321388D02*
Y319289D01*
G01D02*
G03X486755Y318806I683J0D01*
G01D02*
G03X487238Y318606I483J483D01*
G01D02*
X487612D01*
G01X494774Y316281D02*
G02X493855Y318500I2219J2219D01*
G01D02*
Y319800D01*
G01X491257Y315952D02*
X491586Y316281D01*
G01D02*
G03X492505Y318500I-2219J2219D01*
G01D02*
Y319800D01*
G01X487500Y333833D02*
G02X488579Y333386I0J-1526D01*
G01D02*
X489589Y332376D01*
G01D02*
G03X490255Y332100I666J666D01*
G01D02*
X490855D01*
G01D02*
G02X493244Y331111I1J-3378D01*
G01D02*
X494355Y330000D01*
G01X483662Y334054D02*
X484808Y332908D01*
G01D02*
G03X487000Y332000I2192J2192D01*
G01D02*
X487882D01*
G01D02*
G02X488177Y331878I0J-417D01*
G01D02*
X488634Y331421D01*
G01D02*
G03X490255Y330750I1620J1621D01*
G01D02*
X490855D01*
G01D02*
G02X492289Y330156I0J-2028D01*
G01D02*
X493400Y329045D01*
G01D02*
G03X495561Y328150I2161J2162D01*
G01X494612Y323850D02*
X492661Y324694D01*
G01D02*
X489805Y327550D01*
G01D02*
X489764Y327590D01*
G01D02*
G03X488655Y328050I-1110J-1109D01*
G01D02*
X486382D01*
G01D02*
G02X485267Y328512I0J1577D01*
G01D02*
X483662Y330117D01*
G01X487599D02*
X488211Y329503D01*
G01D02*
X488217Y329498D01*
G01D02*
G03X488455Y329400I237J238D01*
G01D02*
X488656D01*
G01D02*
G02X490713Y328552I0J-2919D01*
G01D02*
X493434Y325831D01*
G01D02*
X494892Y325200D01*
G01X487155Y321900D02*
X487067D01*
G01D02*
G03X486705Y321750I0J-512D01*
G01D02*
G03X486555Y321388I362J-362D01*
G01X493855Y319800D02*
G03X492866Y322189I-3378J1D01*
G01D02*
X490209Y324846D01*
G01D02*
X490063Y324993D01*
G01D02*
G03X488468Y325653I-1594J-1595D01*
G01D02*
G02X488123Y325744I86J1025D01*
G01D02*
G02X487828Y325951I434J933D01*
G01D02*
X487599Y326180D01*
G01X492505Y319800D02*
G03X491911Y321234I-2028J0D01*
G01D02*
X489250Y323895D01*
G01D02*
X489192Y323954D01*
G01D02*
G03X488355Y324300I-836J-837D01*
G01D02*
X487455D01*
G01D02*
G02X484190Y325653I1J4618D01*
G01D02*
X483662Y326180D01*
G01X496075Y357043D02*
X491755D01*
G01D02*
Y357044D01*
G01D02*
G03X489434Y356379I-1J-4381D01*
G01D02*
G02X487835Y355760I-1599J1756D01*
G01D02*
G03X486435Y355180I1J-1981D01*
G01D02*
X485726Y354471D01*
G01D02*
G02X483958Y353739I-1768J1769D01*
G01D02*
X483662D01*
G01X496075Y355693D02*
X491755D01*
G01D02*
G03X490149Y355233I-1J-3030D01*
G01D02*
G03X489612Y354806I1605J-2570D01*
G01D02*
X489391Y354584D01*
G01D02*
X488969Y354162D01*
G01D02*
G02X487948Y353739I-1021J1021D01*
G01D02*
X487599D01*
G01X494225Y359500D02*
X487441D01*
G01D02*
G03X485673Y358768I0J-2501D01*
G01D02*
X484906Y358001D01*
G01D02*
G02X484121Y357676I-784J784D01*
G01D02*
X483662D01*
G01X494225Y358150D02*
X489240D01*
G01D02*
G03X488283Y357960I-1J-2500D01*
G01D02*
X487599Y357676D01*
G01X496225Y367743D02*
X494026D01*
G01D02*
G03X491230Y366585I0J-3955D01*
G01D02*
X489555Y364910D01*
G01D02*
G02X488742Y364573I-814J814D01*
G01D02*
X487415D01*
G01D02*
Y364572D01*
G01D02*
G03X486264Y364368I15J-3432D01*
G01D02*
G03X486120Y364314I1133J-3241D01*
G01D02*
X486117Y364313D01*
G01D02*
X484941Y363827D01*
G01D02*
G02X483705Y364340I-361J875D01*
G01D02*
G02X483663Y365463I1494J618D01*
G01X496225Y366393D02*
X494027D01*
G01D02*
G03X492185Y365630I0J-2605D01*
G01D02*
X490510Y363955D01*
G01D02*
G02X488742Y363223I-1768J1769D01*
G01D02*
X487430D01*
G01D02*
G03X487422Y363222I254J-2067D01*
G01D02*
G03X486720Y363097I9J-2082D01*
G01D02*
G03X486633Y363064I695J-1963D01*
G01D02*
X484500Y362181D01*
G01D02*
G03X483688Y361639I955J-2310D01*
G01D02*
X483662Y361613D01*
G01X498597Y374303D02*
X488571D01*
G01D02*
G03X485797Y373125I-1J-3852D01*
G01D02*
X485503Y372643D01*
G01D02*
G03X485195Y371553I1778J-1091D01*
G01D02*
Y371302D01*
G01D02*
G02X484866Y370741I-1243J352D01*
G01D02*
X483793Y369668D01*
G01D02*
G03X483683Y369403I264J-265D01*
G01X498597Y372953D02*
X488571D01*
G01D02*
G03X486864Y372280I0J-2501D01*
G01D02*
X486654Y371937D01*
G01D02*
G03X486545Y371552I627J-385D01*
G01D02*
Y370541D01*
G01D02*
G03X487603Y369483I1058J0D01*
G01X493650Y610000D02*
Y448130D01*
G01D02*
G03X496572Y441073I9978J-2D01*
G01X483673Y608656D02*
Y445929D01*
G01D02*
G02X480642Y438612I-10348J0D01*
G01X485023Y608655D02*
Y445928D01*
G01D02*
G02X481597Y437657I-11698J1D01*
G01X478055Y612383D02*
Y450211D01*
G01X499309Y623665D02*
G03X493649Y610000I13665J-13665D01*
G01D02*
X493650D01*
G01X490300Y624655D02*
G03X483673Y608656I16000J-16000D01*
G01X491255Y623700D02*
G03X485023Y608655I15045J-15045D01*
G01X484855Y628800D02*
G03X478055Y612383I16417J-16417D01*
G01X531072Y665427D02*
X490300Y624655D01*
G01X532027Y664472D02*
X491255Y623700D01*
G01X520072Y665927D02*
X483900Y629755D01*
G01X521029Y664974D02*
X484855Y628800D01*
G01X477862Y881284D02*
X479344Y882766D01*
G01D02*
G02X479909Y883000I565J-565D01*
G01D02*
X480278D01*
G01X490023Y929745D02*
X508423Y911345D01*
G01X485428Y999318D02*
Y940840D01*
G01D02*
G03X490023Y929745I15690J-1D01*
G01X486778Y967692D02*
Y940840D01*
G01D02*
G03X490978Y930700I14340J0D01*
G01D02*
X509378Y912300D01*
G01X487718Y976932D02*
Y975732D01*
G01D02*
G02X487248Y974792I-1140J-18D01*
G01D02*
G03X486778Y973852I670J-923D01*
G01D02*
Y972652D01*
G01D02*
G03X487248Y971712I1140J-18D01*
G01D02*
G02X487718Y970772I-670J-923D01*
G01D02*
Y969572D01*
G01D02*
G02X487248Y968632I-1140J-18D01*
G01D02*
G03X486778Y967692I670J-923D01*
G01Y998331D02*
Y991132D01*
G01D02*
G03X487248Y990192I1140J-18D01*
G01D02*
G02X487718Y989252I-670J-923D01*
G01D02*
Y988052D01*
G01D02*
G02X487248Y987112I-1140J-18D01*
G01D02*
G03X486778Y986172I670J-923D01*
G01D02*
Y984972D01*
G01D02*
G03X487248Y984032I1140J-18D01*
G01D02*
G02X487718Y983092I-670J-923D01*
G01D02*
Y981892D01*
G01D02*
G02X487248Y980952I-1140J-18D01*
G01D02*
G03X486778Y980012I670J-923D01*
G01D02*
Y978812D01*
G01D02*
G03X487248Y977872I1140J-18D01*
G01D02*
G02X487718Y976932I-670J-923D01*
G01X484253Y1009860D02*
Y1002156D01*
G01D02*
G03X484840Y1000738I2006J0D01*
G01D02*
G02X485428Y999318I-1421J-1420D01*
G01X488188Y1009860D02*
Y1002773D01*
G01D02*
G02X487944Y1001696I-2499J0D01*
G01D02*
X487044Y999810D01*
G01D02*
G03X486803Y998857I2256J-1077D01*
G01D02*
X486780Y998391D01*
G01D02*
G03X486778Y998331I1203J-70D01*
G01X500607Y314200D02*
X501285Y314879D01*
G01D02*
G03X501750Y316000I-1121J1122D01*
G01D02*
Y323000D01*
G01X503100D02*
Y315800D01*
G01D02*
G03X504453Y314200I1623J0D01*
G01X495103Y315952D02*
X494774Y316281D01*
G01X494355Y330000D02*
G03X495562Y329500I1207J1207D01*
G01D02*
X507755D01*
G01D02*
G02X510855Y326400I0J-3100D01*
G01X495561Y328150D02*
X507755D01*
G01D02*
G02X509505Y326400I0J-1750D01*
G01D02*
Y321005D01*
G01D02*
X508500Y320000D01*
G01X501750Y323000D02*
G03X500900Y323850I-850J0D01*
G01D02*
X494612D01*
G01X494892Y325200D02*
X500900D01*
G01D02*
G02X503100Y323000I0J-2200D01*
G01X534368Y385668D02*
X510400Y361700D01*
G01D02*
G02X507100Y360333I-3300J3300D01*
G01D02*
X501902D01*
G01D02*
G03X499512Y359343I1J-3381D01*
G01D02*
X498016Y357847D01*
G01D02*
G02X496075Y357043I-1941J1941D01*
G01X511355Y360745D02*
G02X507101Y358983I-4254J4255D01*
G01D02*
X501903D01*
G01D02*
G03X500467Y358388I0J-2031D01*
G01D02*
X498971Y356892D01*
G01D02*
G02X496075Y355693I-2895J2896D01*
G01X527724Y386724D02*
X509083Y368083D01*
G01D02*
G02X506500Y367013I-2583J2583D01*
G01D02*
X505475D01*
G01D02*
G03X503453Y366666I0J-6065D01*
G01D02*
G03X501187Y365237I2022J-5718D01*
G01D02*
X496316Y360366D01*
G01D02*
G02X494225Y359500I-2091J2091D01*
G01X528679Y385769D02*
X510038Y367128D01*
G01D02*
G02X506500Y365663I-3537J3538D01*
G01D02*
X505476D01*
G01D02*
G03X503903Y365393I0J-4715D01*
G01D02*
Y365392D01*
G01D02*
G03X502142Y364282I1571J-4445D01*
G01D02*
X497271Y359411D01*
G01D02*
G02X494225Y358150I-3045J3047D01*
G01X498393Y368641D02*
G02X496225Y367743I-2168J2168D01*
G01X504021Y372359D02*
X499348Y367686D01*
G01D02*
G02X496225Y366393I-3122J3123D01*
G01X521221Y386221D02*
X510500Y375500D01*
G01D02*
G02X508100Y374506I-2400J2400D01*
G01D02*
X505944D01*
G01D02*
G03X503066Y373314I0J-4071D01*
G01D02*
X498393Y368641D01*
G01X511455Y374545D02*
G02X508100Y373156I-3354J3355D01*
G01D02*
X505945D01*
G01D02*
G03X504021Y372359I0J-2721D01*
G01X514750Y385350D02*
X509800Y380400D01*
G01D02*
G02X507296Y379363I-2504J2504D01*
G01D02*
X506032D01*
G01D02*
G03X502792Y378022I-2J-4580D01*
G01D02*
X502791D01*
G01D02*
X499410Y374641D01*
G01D02*
G02X498597Y374303I-815J812D01*
G01X510755Y379445D02*
G02X507295Y378013I-3458J3459D01*
G01D02*
X506031D01*
G01D02*
G03X503747Y377067I0J-3230D01*
G01D02*
X500365Y373685D01*
G01D02*
G02X498597Y372953I-1768J1769D01*
G01X496572Y441073D02*
X512701Y424944D01*
G01X497527Y442028D02*
X513656Y425899D01*
G01X507500Y453999D02*
G03X510679Y446323I10857J0D01*
G01X508850Y454000D02*
G03X511635Y447278I9507J1D01*
G01X500500Y453289D02*
G03X504977Y442478I15287J-2D01*
G01D02*
X504976Y442477D01*
G01D02*
X519476Y427977D01*
G01X501850Y453288D02*
G03X505932Y443433I13937J0D01*
G01D02*
X520432Y428933D01*
G01X495000Y610000D02*
Y448129D01*
G01D02*
G03X497527Y442028I8628J0D01*
G01X507500Y573500D02*
Y453999D01*
G01X508850Y472770D02*
Y454000D01*
G01X500500Y576745D02*
Y453289D01*
G01X501850Y576744D02*
Y453288D01*
G01X508850Y483890D02*
G03X509320Y482950I1140J-18D01*
G01D02*
G02X509790Y482010I-670J-923D01*
G01D02*
Y480810D01*
G01D02*
G02X509320Y479870I-1140J-18D01*
G01D02*
G03X508850Y478930I670J-923D01*
G01D02*
Y477730D01*
G01D02*
G03X509320Y476790I1140J-18D01*
G01D02*
G02X509790Y475850I-670J-923D01*
G01D02*
Y474650D01*
G01D02*
G02X509320Y473710I-1140J-18D01*
G01D02*
G03X508850Y472770I670J-923D01*
G01Y553323D02*
Y490050D01*
G01D02*
G03X509320Y489110I1140J-18D01*
G01D02*
G02X509790Y488170I-670J-923D01*
G01D02*
Y486970D01*
G01D02*
G02X509320Y486030I-1140J-18D01*
G01D02*
G03X508850Y485090I670J-923D01*
G01D02*
Y483890D01*
G01Y573500D02*
Y558283D01*
G01D02*
G03X509320Y557343I1140J-18D01*
G01D02*
G02X509790Y556403I-670J-922D01*
G01D02*
Y555203D01*
G01D02*
G02X509320Y554263I-1140J-18D01*
G01D02*
G03X508850Y553323I670J-922D01*
G01X570045Y639955D02*
X510264Y580174D01*
G01D02*
G03X507500Y573500I6674J-6673D01*
G01X511219Y579219D02*
G03X508850Y573500I5719J-5719D01*
G01X502771Y582228D02*
G03X500500Y576745I5484J-5483D01*
G01X554476Y632023D02*
X503726Y581273D01*
G01D02*
G03X501850Y576744I4529J-4529D01*
G01X553521Y632978D02*
X502771Y582228D01*
G01X500264Y622710D02*
G03X495000Y610000I12710J-12709D01*
G01X539572Y663927D02*
X501572Y625927D01*
G01D02*
X499309Y623665D01*
G01X540527Y662972D02*
X502527Y624972D01*
G01D02*
X500264Y622710D01*
G01X508423Y911345D02*
G02X514296Y897166I-14179J-14179D01*
G01X501428Y934842D02*
G03X506346Y922969I16792J1D01*
G01D02*
X518196Y911119D01*
G01X502778Y934843D02*
G03X507301Y923924I15442J0D01*
G01D02*
X519151Y912074D01*
G01X509378Y912300D02*
G02X515646Y897166I-15134J-15133D01*
G01X501428Y998590D02*
Y934842D01*
G01X502778Y962593D02*
Y934843D01*
G01X503718Y976793D02*
G02X503248Y975853I-1140J-17D01*
G01D02*
G03X502778Y974913I670J-922D01*
G01D02*
Y973713D01*
G01D02*
G03X503248Y972773I1140J-17D01*
G01D02*
G02X503718Y971833I-670J-922D01*
G01D02*
Y970633D01*
G01D02*
G02X503248Y969693I-1140J-17D01*
G01D02*
G03X502778Y968753I670J-922D01*
G01D02*
Y967553D01*
G01D02*
G03X503248Y966613I1140J-17D01*
G01D02*
G02X503718Y965673I-670J-922D01*
G01D02*
Y964473D01*
G01D02*
G02X503248Y963533I-1140J-17D01*
G01D02*
G03X502778Y962593I670J-922D01*
G01Y998980D02*
Y979873D01*
G01D02*
G03X503248Y978933I1140J-17D01*
G01D02*
G02X503718Y977993I-670J-922D01*
G01D02*
Y976793D01*
G01X499998Y1009860D02*
Y1003041D01*
G01D02*
G03X500188Y1002085I2500J0D01*
G01D02*
X501238Y999546D01*
G01D02*
G02X501415Y998841I-2310J-955D01*
G01D02*
G02X501428Y998590I-2487J-255D01*
G01X503938Y1009860D02*
Y1001780D01*
G01D02*
G02X503358Y1000380I-1980J0D01*
G01D02*
G03X502778Y998980I1400J-1400D01*
G01X510855Y326400D02*
Y321145D01*
G01D02*
X512000Y320000D01*
G01X535323Y384713D02*
X511355Y360745D01*
G01X522176Y385266D02*
X511455Y374545D01*
G01X517055Y387657D02*
G02X515705Y384395I-4611J-2D01*
G01D02*
X510755Y379445D01*
G01X522455Y420789D02*
Y389200D01*
G01D02*
G02X521221Y386221I-4213J0D01*
G01X523805Y420790D02*
Y389199D01*
G01D02*
G02X522176Y385266I-5563J0D01*
G01X515705Y417693D02*
Y387656D01*
G01D02*
G02X514750Y385350I-3261J0D01*
G01X517055Y417693D02*
Y387657D01*
G01X512701Y424944D02*
G02X515705Y417693I-7251J-7252D01*
G01X513656Y425899D02*
G02X517055Y417693I-8206J-8206D01*
G01X510679Y446323D02*
X526751Y430251D01*
G01D02*
G02X529205Y424327I-5924J-5924D01*
G01X512456Y446456D02*
X527706Y431206D01*
G01X519476Y427977D02*
X519477Y427978D01*
G01D02*
G02X522455Y420789I-7188J-7189D01*
G01X520432Y428933D02*
G02X523805Y420790I-8143J-8143D01*
G01X511635Y447278D02*
X512456Y446456D01*
G01X571000Y639000D02*
X511219Y579219D01*
G01X522296Y901221D02*
Y671000D01*
G01D02*
G02X520281Y666137I-6878J1D01*
G01D02*
X520072Y665927D01*
G01X523646Y823233D02*
Y670999D01*
G01D02*
G02X521237Y665183I-8228J1D01*
G01D02*
X521029Y664974D01*
G01X514296Y897166D02*
Y676089D01*
G01D02*
G02X512572Y671927I-5886J0D01*
G01X515646Y835675D02*
Y676088D01*
G01D02*
G02X513527Y670972I-7236J0D01*
G01X523646Y829393D02*
Y828193D01*
G01D02*
G03X524116Y827253I1140J-18D01*
G01D02*
G02X524586Y826313I-670J-922D01*
G01D02*
Y825113D01*
G01D02*
G02X524116Y824173I-1140J-18D01*
G01D02*
G03X523646Y823233I670J-922D01*
G01X524586Y844793D02*
Y843593D01*
G01D02*
G02X524116Y842653I-1140J-18D01*
G01D02*
G03X523646Y841713I670J-922D01*
G01D02*
Y840513D01*
G01D02*
G03X524116Y839573I1140J-18D01*
G01D02*
G02X524586Y838633I-670J-922D01*
G01D02*
Y837433D01*
G01D02*
G02X524116Y836493I-1140J-18D01*
G01D02*
G03X523646Y835553I670J-922D01*
G01D02*
Y834353D01*
G01D02*
G03X524116Y833413I1140J-18D01*
G01D02*
G02X524586Y832473I-670J-922D01*
G01D02*
Y831273D01*
G01D02*
G02X524116Y830333I-1140J-18D01*
G01D02*
G03X523646Y829393I670J-922D01*
G01X516586Y844915D02*
Y843715D01*
G01D02*
G02X516116Y842775I-1140J-18D01*
G01D02*
G03X515646Y841835I670J-922D01*
G01D02*
Y840635D01*
G01D02*
G03X516116Y839695I1140J-18D01*
G01D02*
G02X516586Y838755I-670J-922D01*
G01D02*
Y837555D01*
G01D02*
G02X516116Y836615I-1140J-18D01*
G01D02*
G03X515646Y835675I670J-922D01*
G01X523646Y901222D02*
Y846673D01*
G01D02*
G03X524116Y845733I1140J-18D01*
G01D02*
G02X524586Y844793I-670J-922D01*
G01X515646Y897166D02*
Y852955D01*
G01D02*
G03X516116Y852015I1140J-18D01*
G01D02*
G02X516586Y851075I-670J-922D01*
G01D02*
Y849875D01*
G01D02*
G02X516116Y848935I-1140J-18D01*
G01D02*
G03X515646Y847995I670J-922D01*
G01D02*
Y846795D01*
G01D02*
G03X516116Y845855I1140J-18D01*
G01D02*
G02X516586Y844915I-670J-922D01*
G01X518196Y911119D02*
G02X522296Y901221I-9898J-9898D01*
G01X519151Y912074D02*
G02X523646Y901222I-10853J-10852D01*
G01X517028Y934200D02*
G03X524777Y915491I26458J-1D01*
G01D02*
X526023Y914245D01*
G01D02*
G02X526986Y913225I-17567J-17550D01*
G01X518378Y934200D02*
G03X525732Y916446I25108J0D01*
G01D02*
X526978Y915200D01*
G01X517028Y998945D02*
Y934200D01*
G01X518378Y971420D02*
Y934200D01*
G01Y976380D02*
G03X518848Y975440I1140J-18D01*
G01D02*
G02X519318Y974500I-670J-923D01*
G01D02*
Y973300D01*
G01D02*
G02X518848Y972360I-1140J-18D01*
G01D02*
G03X518378Y971420I670J-923D01*
G01Y998478D02*
Y988700D01*
G01D02*
G03X518848Y987760I1140J-18D01*
G01D02*
G02X519318Y986820I-670J-923D01*
G01D02*
Y985620D01*
G01D02*
G02X518848Y984680I-1140J-18D01*
G01D02*
G03X518378Y983740I670J-923D01*
G01D02*
Y982540D01*
G01D02*
G03X518848Y981600I1140J-18D01*
G01D02*
G02X519318Y980660I-670J-923D01*
G01D02*
Y979460D01*
G01D02*
G02X518848Y978520I-1140J-18D01*
G01D02*
G03X518378Y977580I670J-923D01*
G01D02*
Y976380D01*
G01X515748Y1009860D02*
Y1002035D01*
G01D02*
G03X516388Y1000490I2185J0D01*
G01D02*
G02X517028Y998945I-1545J-1545D01*
G01X519683Y1009860D02*
Y1001628D01*
G01D02*
G02X519030Y1000053I-2228J1D01*
G01D02*
X519029Y1000052D01*
G01D02*
G03X518378Y998478I1577J-1574D01*
G01X537305Y389499D02*
G02X535323Y384713I-6770J0D01*
G01X535955Y570847D02*
Y389500D01*
G01D02*
G02X534368Y385668I-5420J0D01*
G01X537305Y462214D02*
Y389499D01*
G01X529205Y424327D02*
Y390300D01*
G01D02*
G02X527724Y386724I-5058J0D01*
G01X530555Y424328D02*
Y390299D01*
G01D02*
G02X528679Y385769I-6408J0D01*
G01X527706Y431206D02*
G02X530555Y424328I-6879J-6879D01*
G01X537305Y467174D02*
G03X537775Y466234I1140J-18D01*
G01D02*
G02X538245Y465294I-670J-922D01*
G01D02*
Y464094D01*
G01D02*
G02X537775Y463154I-1140J-18D01*
G01D02*
G03X537305Y462214I670J-922D01*
G01Y531241D02*
Y479494D01*
G01D02*
G03X537775Y478554I1140J-18D01*
G01D02*
G02X538245Y477614I-670J-922D01*
G01D02*
Y476414D01*
G01D02*
G02X537775Y475474I-1140J-18D01*
G01D02*
G03X537305Y474534I670J-922D01*
G01D02*
Y473334D01*
G01D02*
G03X537775Y472394I1140J-18D01*
G01D02*
G02X538245Y471454I-670J-922D01*
G01D02*
Y470254D01*
G01D02*
G02X537775Y469314I-1140J-18D01*
G01D02*
G03X537305Y468374I670J-922D01*
G01D02*
Y467174D01*
G01X538245Y533121D02*
G02X537775Y532181I-1140J-18D01*
G01D02*
G03X537305Y531241I670J-922D01*
G01Y570847D02*
Y536201D01*
G01D02*
G03X537775Y535261I1140J-18D01*
G01D02*
G02X538245Y534321I-670J-922D01*
G01D02*
Y533121D01*
G01X580045Y618955D02*
X538795Y577705D01*
G01D02*
G03X535955Y570847I6858J-6857D01*
G01X580999Y617999D02*
X539750Y576750D01*
G01D02*
G03X537305Y570847I5903J-5903D01*
G01X541796Y669296D02*
G02X539572Y663927I-7593J0D01*
G01X543146Y669295D02*
G02X540527Y662972I-8943J0D01*
G01X541796Y909705D02*
Y669296D01*
G01X543146Y909706D02*
Y669295D01*
G01X533296Y896686D02*
Y670796D01*
G01D02*
G02X531072Y665427I-7593J0D01*
G01X534646Y860748D02*
Y670795D01*
G01D02*
G02X532027Y664472I-8943J0D01*
G01X535116Y861688D02*
G03X534646Y860748I670J-922D01*
G01Y878028D02*
G03X535116Y877088I1140J-18D01*
G01D02*
G02X535586Y876148I-670J-922D01*
G01D02*
Y874948D01*
G01D02*
G02X535116Y874008I-1140J-18D01*
G01D02*
G03X534646Y873068I670J-922D01*
G01D02*
Y871868D01*
G01D02*
G03X535116Y870928I1140J-18D01*
G01D02*
G02X535586Y869988I-670J-922D01*
G01D02*
Y868788D01*
G01D02*
G02X535116Y867848I-1140J-18D01*
G01D02*
G03X534646Y866908I670J-922D01*
G01D02*
Y865708D01*
G01D02*
G03X535116Y864768I1140J-18D01*
G01D02*
G02X535586Y863828I-670J-922D01*
G01D02*
Y862628D01*
G01D02*
G02X535116Y861688I-1140J-18D01*
G01X534646Y896686D02*
Y884188D01*
G01D02*
G03X535116Y883248I1140J-18D01*
G01D02*
G02X535586Y882308I-670J-922D01*
G01D02*
Y881108D01*
G01D02*
G02X535116Y880168I-1140J-18D01*
G01D02*
G03X534646Y879228I670J-922D01*
G01D02*
Y878028D01*
G01X537428Y920250D02*
G02X541796Y909705I-10545J-10545D01*
G01X538383Y921205D02*
G02X543146Y909706I-11500J-11499D01*
G01X526986Y913225D02*
G02X533296Y896686I-18522J-16540D01*
G01X527994Y914125D02*
G02X534646Y896686I-19530J-17438D01*
G01X532488Y930055D02*
G03X535928Y921750I11746J0D01*
G01D02*
X537428Y920250D01*
G01X533838Y930056D02*
G03X536883Y922705I10396J0D01*
G01D02*
X538383Y921205D01*
G01X526978Y915200D02*
G02X527994Y914125I-18513J-18514D01*
G01X532488Y999362D02*
Y930055D01*
G01X533838Y998129D02*
Y930056D01*
G01X531498Y1009860D02*
Y1001233D01*
G01D02*
G03X531868Y1000340I1263J0D01*
G01D02*
X531975Y1000199D01*
G01D02*
G03X532196Y999944I1995J1506D01*
G01D02*
X532282Y999858D01*
G01D02*
G02X532488Y999362I-495J-496D01*
G01X535433Y1009860D02*
Y1002031D01*
G01D02*
G02X534701Y1000263I-2501J0D01*
G01D02*
X534581Y1000143D01*
G01D02*
G03X534396Y999866I603J-603D01*
G01D02*
X533988Y998881D01*
G01D02*
G03X533838Y998129I1814J-753D01*
G01X556650Y975607D02*
Y640530D01*
G01D02*
X556649Y640531D01*
G01D02*
G02X553521Y632978I-10681J-1D01*
G01X558000Y999293D02*
Y640531D01*
G01D02*
G02X554476Y632023I-12032J0D01*
G01X556180Y976547D02*
G02X556650Y975607I-670J-922D01*
G01Y998652D02*
Y980567D01*
G01D02*
G02X556180Y979627I-1140J-18D01*
G01D02*
G03X555710Y978687I670J-922D01*
G01D02*
Y977487D01*
G01D02*
G03X556180Y976547I1140J-18D01*
G01X555118Y1009860D02*
Y1000922D01*
G01D02*
G03X555500Y1000000I1304J0D01*
G01D02*
X555646Y999853D01*
G01D02*
G03X556038Y999592I852J855D01*
G01D02*
G02X556307Y999480I-1J-381D01*
G01D02*
G02X556650Y998652I-828J-828D01*
G01X559053Y1009860D02*
Y1001835D01*
G01D02*
G02X558500Y1000500I-1888J0D01*
G01D02*
G03X558102Y999874I1207J-1207D01*
G01D02*
G03X558067Y999767I1604J-584D01*
G01D02*
Y999766D01*
G01D02*
G03X558005Y999431I1639J-477D01*
G01D02*
G03X558000Y999293I1702J-131D01*
G01X572033Y999186D02*
Y644754D01*
G01D02*
G02X570045Y639955I-6787J0D01*
G01X573383Y996100D02*
Y644753D01*
G01D02*
G02X571000Y639000I-8137J1D01*
G01X570868Y1009860D02*
Y1001834D01*
G01D02*
G03X571450Y1000427I1989J-1D01*
G01D02*
X571567Y1000311D01*
G01D02*
G02X572033Y999186I-1123J-1124D01*
G01X574803Y1009860D02*
Y1002889D01*
G01D02*
G02X574613Y1001933I-2500J0D01*
G01D02*
X574400Y1001418D01*
G01D02*
G03X573383Y996100I13396J-5318D01*
G01X582428Y982984D02*
Y624000D01*
G01D02*
G02X580546Y619455I-6427J-1D01*
G01D02*
X580045Y618955D01*
G01X583778Y982984D02*
Y624000D01*
G01D02*
X583779D01*
G01D02*
G02X581501Y618499I-7778J-1D01*
G01D02*
X580999Y617999D01*
G01X588198Y993027D02*
G02X587400Y991100I-2725J0D01*
G01D02*
X584650Y988350D01*
G01D02*
G03X582428Y982984I5366J-5365D01*
G01X589548Y993027D02*
G02X588355Y990145I-4075J-1D01*
G01D02*
X585605Y987395D01*
G01D02*
G03X583778Y982984I4411J-4411D01*
G01X586613Y1009860D02*
Y1002101D01*
G01D02*
G03X587345Y1000333I2501J0D01*
G01D02*
X587466Y1000212D01*
G01D02*
G02X588198Y998444I-1769J-1768D01*
G01D02*
Y993027D01*
G01X590553Y1009860D02*
Y1001583D01*
G01D02*
G02X590363Y1000626I-2500J-1D01*
G01D02*
X590050Y999872D01*
G01D02*
X589669Y998951D01*
G01D02*
G03X589548Y998345I1462J-607D01*
G01D02*
Y993027D01*
G01X1152025Y763975D02*
X1149400Y766600D01*
G01D02*
Y770279D01*
G01D02*
X1147564Y772115D01*
G01D02*
Y777051D01*
G01D02*
X1145970Y778645D01*
G01D02*
X1144839D01*
G01D02*
X1143234Y780250D01*
G01X1153375Y764535D02*
X1150750Y767160D01*
G01Y770839D02*
X1148914Y772675D01*
G01D02*
Y777611D01*
G01D02*
X1146530Y779995D01*
G01X1143234Y780250D02*
X1142323D01*
G01X1146530Y779995D02*
X1145399D01*
G01D02*
X1143470Y781924D01*
G01D02*
Y782805D01*
G01X1152400Y727600D02*
Y727808D01*
G01D02*
X1153547Y728955D01*
G01D02*
X1153697D01*
G01D02*
X1155300Y730558D01*
G01X1152745Y741345D02*
X1151900Y740500D01*
G01X1152745Y741345D02*
X1152025Y742065D01*
G01D02*
Y745585D01*
G01D02*
X1153215Y746775D01*
G01X1152248Y730404D02*
X1153236D01*
G01D02*
X1153950Y731118D01*
G01D02*
Y740140D01*
G01D02*
X1152745Y741345D01*
G01X1156700Y745425D02*
Y744100D01*
G01Y745425D02*
X1157425D01*
G01D02*
X1158900Y746900D01*
G01X1155300Y730558D02*
Y739580D01*
G01D02*
X1155301Y739581D01*
G01D02*
Y740699D01*
G01D02*
X1153375Y742625D01*
G01D02*
Y745025D01*
G01D02*
X1153775Y745425D01*
G01D02*
X1156700D01*
G01X1157500Y739200D02*
X1157700Y739000D01*
G01D02*
Y735800D01*
G01D02*
X1157000Y735100D01*
G01D02*
Y734500D01*
G01X1160000Y734480D02*
X1159280D01*
G01D02*
X1157112Y732312D01*
G01D02*
Y731702D01*
G01X1153215Y746775D02*
X1156865D01*
G01D02*
X1157550Y747460D01*
G01D02*
Y748240D01*
G01D02*
X1156615Y749175D01*
G01D02*
X1153215D01*
G01D02*
X1152025Y750365D01*
G01D02*
Y753885D01*
G01D02*
X1153215Y755075D01*
G01D02*
X1153950D01*
G01D02*
X1154850Y755975D01*
G01D02*
Y757540D01*
G01D02*
X1154240Y758150D01*
G01D02*
X1153540D01*
G01D02*
X1152025Y759665D01*
G01D02*
Y763975D01*
G01X1158900Y746900D02*
Y748800D01*
G01D02*
X1157175Y750525D01*
G01D02*
X1153775D01*
G01D02*
X1153375Y750925D01*
G01D02*
Y753325D01*
G01D02*
X1153775Y753725D01*
G01D02*
X1154510D01*
G01D02*
X1156200Y755415D01*
G01D02*
Y758100D01*
G01D02*
X1154800Y759500D01*
G01D02*
X1154100D01*
G01D02*
X1153375Y760225D01*
G01D02*
Y764535D01*
G01X1150750Y767160D02*
Y770839D01*
G01X1163600Y777900D02*
X1163186D01*
G01D02*
X1162693Y778393D01*
G01D02*
Y780865D01*
G01X1168292Y779808D02*
X1167143Y780957D01*
G01D02*
X1165492D01*
G01X1168465Y779808D02*
X1168292D01*
G54D11*
G01X1Y-17717D02*
G03X7875Y-25591I7874J0D01*
G01X1Y299252D02*
Y-10394D01*
G01Y-17717D02*
G03X7875Y-25591I7874J0D01*
G01X1Y299252D02*
Y-10394D01*
G01Y-17717D02*
Y-10394D01*
G01D02*
Y-17723D01*
G01X0Y11811D02*
Y0D01*
G01X92520Y299252D02*
X1D01*
G01X92520D02*
X1D01*
G01X1008465Y988189D02*
G03X988780Y968504I0J-19685D01*
G01Y775591D01*
G02X984843Y771654I-3937J0D01*
G01X925787D01*
G02X921850Y775591I0J3937D01*
G01Y968504D01*
G03X902165Y988189I-19685J0D01*
G01X800984D01*
G02X797047Y992126I0J3937D01*
G01Y1021653D01*
X795078Y1023622D01*
X754921D01*
X752952Y1021653D01*
X752953Y1018110D01*
Y994291D01*
G02X745472I-3740J0D01*
G01Y1021653D01*
X743504Y1023622D01*
X719094D01*
X717126Y1021653D01*
Y992126D01*
G02X713189Y988189I-3937J0D01*
G01X600984D01*
G02X597047Y992126I0J3937D01*
G01Y1021653D01*
X595078Y1023622D01*
X554921D01*
X552952Y1021653D01*
X552953Y1018110D01*
Y994291D01*
G02X545472I-3741J0D01*
G01Y1021653D01*
X543504Y1023622D01*
X267126D01*
X265157Y1021653D01*
Y992126D01*
G02X261220Y988189I-3937J0D01*
G01X191535D01*
G02X187598Y992126I0J3937D01*
G01Y1021653D01*
X185630Y1023622D01*
X145472D01*
X143504Y1021653D01*
Y994291D01*
G02X136024I-3740J0D01*
G01Y1018110D01*
X136023Y1021653D01*
X134055Y1023622D01*
X109645D01*
X107677Y1021653D01*
Y992126D01*
G02X103740Y988189I-3937J0D01*
G01X19685D01*
G03X0Y968504I0J-19685D01*
G01Y318937D01*
G03X11811Y307126I11811J0D01*
G01X100394D01*
G02X108268Y299252I0J-7874D01*
G01Y236260D01*
G03X116142Y228386I7874J0D01*
G01X239961D01*
G02X243898Y224449I0J-3937D01*
G01Y70866D01*
G03X247835Y66929I3937J0D01*
G01X289173D01*
G02X293110Y62992I0J-3937D01*
G01Y3937D01*
G03X297047Y0I3937J0D01*
G01X1108209D01*
G03X1112146Y3937I0J3937D01*
G01Y210630D01*
G02X1116083Y214567I3937J0D01*
G01X1194823D01*
G02X1198760Y210630I0J-3937D01*
G01Y179134D01*
G03X1202697Y175197I3937J0D01*
G02X1206634Y171260I0J-3937D01*
G01Y3937D01*
G03X1210571Y0I3937J0D01*
G01X1396063D01*
G03X1400000Y3937I0J3937D01*
G01Y968504D01*
G03X1380315Y988189I-19685J0D01*
G01X1008465D01*
G01X0Y318937D02*
G03X11811Y307126I11811J0D01*
G01X0Y968503D02*
Y318937D01*
G01X19685Y988189D02*
G03X0Y968503I0J-19685D01*
G01X43950Y996063D02*
X1D01*
G01X43950D02*
X1D01*
G01Y1008622D02*
Y996063D01*
G01Y1008622D02*
Y996063D01*
G01X15001Y1023622D02*
G03X1Y1008622I0J-15000D01*
G01X15001Y1023622D02*
G03X1Y1008622I0J-15000D01*
G01X7875Y-25591D02*
X45337D01*
G01X7875D02*
X45337D01*
G01X11811Y307126D02*
X100394D01*
G01X10710Y1008622D02*
G03X19292I4291J0D01*
G01D02*
G03X10710I-4291J0D01*
G01X99804Y1023622D02*
X15001D01*
G01X99804D02*
X15001D01*
G01X103740Y988189D02*
X19685D01*
G01X53211Y-25591D02*
G03X45337I-3937J0D01*
G01X53211D02*
G03X45337I-3937J0D01*
G01X53211D02*
G03X45337I-3937J0D01*
G01X53211D02*
G03X45337I-3937J0D01*
G01X43950Y988189D02*
G03Y996063I0J3937D01*
G01Y988189D02*
G03Y996063I0J3937D01*
G01X53211Y-25591D02*
X1392127D01*
G01X53211D02*
X1392127D01*
G01X69147Y996063D02*
G03Y988189I0J-3937D01*
G01Y996063D02*
G03Y988189I0J-3937D01*
G01X99804Y996063D02*
X69147D01*
G01X99804D02*
X69147D01*
G01X94412Y72220D02*
G03X85830Y72219I-4291J-1D01*
G01D02*
G03X94412Y72220I4291J0D01*
G01X100394Y291377D02*
G03X92520Y299252I-7874J1D01*
G01X100394Y291377D02*
G03X92520Y299252I-7874J1D01*
G01X99804Y1023622D02*
Y996063D01*
G01Y1023622D02*
Y996063D01*
G01X100394Y236259D02*
G03X116142Y220511I15748J0D01*
G01D02*
X232088D01*
G01X100394Y236259D02*
G03X116142Y220511I15748J0D01*
G01D02*
X232088D01*
G01X116142Y228385D02*
X239961D01*
G01X108268Y236259D02*
G03X116142Y228385I7874J0D01*
G01X108268Y299252D02*
Y236259D01*
G01X100395Y240899D02*
X100394Y236259D01*
G01X100395Y240899D02*
X100394Y236259D01*
G01X108269Y240899D02*
G03X100395I-3937J0D01*
G01X108269D02*
G03X100395I-3937J0D01*
G01Y266096D02*
G03X108269I3937J-1D01*
G01X100395D02*
G03X108269I3937J-1D01*
G01X100395D02*
X100394Y291377D01*
G01X100395Y266096D02*
X100394Y291377D01*
G01X108268Y299252D02*
G03X100394Y307126I-7874J0D01*
G01X103740Y988189D02*
G03X107677Y992126I0J3937D01*
G01Y1018109D02*
Y992126D01*
G01X136024Y1018109D02*
X136023Y1021653D01*
X134055Y1023622D01*
X109645D01*
X107677Y1021653D01*
Y1018109D01*
G01X136024Y994290D02*
G03X143505I3740J0D01*
G01X136024D02*
Y1018109D01*
G01X143504D02*
Y994290D01*
G01X187598Y1018109D02*
Y1021653D01*
X185630Y1023622D01*
X145472D01*
X143504Y1021653D01*
Y1018109D01*
G01X151575Y220511D02*
X226378D01*
G01X151575D02*
X226378D01*
G01X187598Y992126D02*
Y1018109D01*
G01Y992126D02*
G03X191535Y988189I3937J0D01*
G01X261220D02*
X191535D01*
G01X212681Y996063D02*
X195473D01*
G01D02*
Y1023622D01*
G01X212681Y996063D02*
X195473D01*
G01D02*
Y1023622D01*
G01D02*
X257284D01*
G01X195473D02*
X257284D01*
G01X212681Y988189D02*
G03Y996063I0J3937D01*
G01Y988189D02*
G03Y996063I0J3937D01*
G01X222751Y1008622D02*
G03X231333I4291J0D01*
G01D02*
G03X222751I-4291J0D01*
G01X243898Y70866D02*
G03X247835Y66928I3937J-1D01*
G01X243898Y224448D02*
Y70866D01*
G01X236025Y164487D02*
Y70866D01*
G01D02*
G03X247836Y59055I11811J0D01*
G01X236025Y164487D02*
Y70866D01*
G01D02*
G03X247836Y59055I11811J0D01*
G01X243899Y164487D02*
G03X236025I-3937J0D01*
G01X243899D02*
G03X236025I-3937J0D01*
G01Y189684D02*
G03X243899I3937J0D01*
G01X236025D02*
G03X243899I3937J0D01*
G01X236025D02*
Y216574D01*
G01Y189684D02*
Y216574D01*
G01D02*
G03X232088Y220511I-3937J0D01*
G01X236025Y216574D02*
G03X232088Y220511I-3937J0D01*
G01X243898Y224448D02*
G03X239961Y228385I-3937J0D01*
G01X237877Y996063D02*
G03Y988189I0J-3937D01*
G01Y996063D02*
G03Y988189I0J-3937D01*
G01X257284Y996063D02*
X237877D01*
G01X257284D02*
X237877D01*
G01X247835Y66929D02*
X289174D01*
G01X247836Y59055D02*
X285237D01*
G01X247836D02*
X285237D01*
G01X261220Y988189D02*
G03X265157Y992126I0J3937D01*
G01X257284Y1023622D02*
Y996063D01*
G01Y1023622D02*
Y996063D01*
G01X265157Y1018109D02*
Y992126D01*
G01X545472Y1018109D02*
Y1021653D01*
X543504Y1023622D01*
X267126D01*
X265157Y1021653D01*
Y1018109D01*
G01X293111Y3937D02*
G03X297047Y0I3937J0D01*
G01X293110Y62992D02*
Y3937D01*
G01X285237D02*
G03X297048Y-7874I11811J0D01*
G01X285237Y59055D02*
Y3937D01*
G01D02*
G03X297048Y-7874I11811J0D01*
G01X285237Y59055D02*
Y3937D01*
G01X293111Y62992D02*
G03X289174Y66929I-3937J0D01*
G01X297047Y0D02*
X1108209D01*
G01X297037Y-7874D02*
X301187D01*
G01D02*
G03Y0I0J3937D01*
G01X297037Y-7874D02*
X301187D01*
G01D02*
G03Y0I0J3937D01*
G01X318510Y-7874D02*
X515333D01*
G01X318510Y0D02*
G03Y-7874I0J-3937D01*
G01D02*
X515333D01*
G01X318510Y0D02*
G03Y-7874I0J-3937D01*
G01X515302D02*
G03Y0I0J3937D01*
G01Y-7874D02*
G03Y0I0J3937D01*
G01X540499Y-7874D02*
X727049D01*
G01X540499Y0D02*
G03Y-7874I0J-3937D01*
G01D02*
X727049D01*
G01X540499Y0D02*
G03Y-7874I0J-3937D01*
G01X545472Y994290D02*
G03X552953I3740J1D01*
G01X545472D02*
Y1018109D01*
G01X552953D02*
Y994290D01*
G01X597047Y1018109D02*
Y1021653D01*
X595078Y1023622D01*
X554921D01*
X552952Y1021653D01*
X552953Y1018109D01*
G01X597047Y992126D02*
Y1018109D01*
G01X597048Y992126D02*
G03X600984Y988189I3937J0D01*
G01X713189D02*
X600984D01*
G01X641198Y996063D02*
X604922D01*
G01D02*
Y1023622D01*
G01X641198Y996063D02*
X604922D01*
G01D02*
Y1023622D01*
G01D02*
X709253D01*
G01X604922D02*
X709253D01*
G01X641198Y988189D02*
G03Y996063I0J3937D01*
G01Y988189D02*
G03Y996063I0J3937D01*
G01X649684Y1008622D02*
G03X658266I4291J0D01*
G01D02*
G03X649684I-4291J0D01*
G01X666395Y996063D02*
G03Y988189I0J-3937D01*
G01Y996063D02*
G03Y988189I0J-3937D01*
G01X709253Y996063D02*
X666395D01*
G01X709253D02*
X666395D01*
G01X713189Y988189D02*
G03X717126Y992126I0J3937D01*
G01Y1018109D02*
Y992126D01*
G01X709253Y1023622D02*
Y996063D01*
G01Y1023622D02*
Y996063D01*
G01X745472Y1018109D02*
Y1021653D01*
X743504Y1023622D01*
X719094D01*
X717126Y1021653D01*
Y1018109D01*
G01X727049Y-7874D02*
G03Y0I0J3937D01*
G01Y-7874D02*
G03Y0I0J3937D01*
G01X752246Y-7874D02*
X984201D01*
G01X752246Y0D02*
G03Y-7874I0J-3937D01*
G01D02*
X984201D01*
G01X752246Y0D02*
G03Y-7874I0J-3937D01*
G01X745472Y994290D02*
G03X752953I3741J1D01*
G01X745472D02*
Y1018109D01*
G01X752953D02*
Y994290D01*
G01X797047Y1018109D02*
Y1021653D01*
X795078Y1023622D01*
X754921D01*
X752952Y1021653D01*
X752953Y1018109D01*
G01X797047Y992126D02*
Y1018109D01*
G01X797048Y992126D02*
G03X800984Y988189I3937J0D01*
G01X902165D02*
X800984D01*
G01X859109Y996063D02*
X804922D01*
G01D02*
Y1023622D01*
G01X859109Y996063D02*
X804922D01*
G01D02*
Y1023622D01*
G01D02*
X1325399D01*
G01X804922D02*
X1325399D01*
G01X859109Y988189D02*
G03Y996063I0J3937D01*
G01Y988189D02*
G03Y996063I0J3937D01*
G01X884306D02*
G03Y988189I0J-3937D01*
G01Y996063D02*
G03Y988189I0J-3937D01*
G01X902166Y996063D02*
X884306D01*
G01X902166D02*
X884306D01*
G01X921850Y968503D02*
G03X902165Y988189I-19685J1D01*
G01X929725Y968504D02*
G03X902166Y996063I-27559J0D01*
G01D02*
X902195D01*
G01X929725Y968504D02*
G03X902166Y996063I-27559J0D01*
G01D02*
X902195D01*
G01X921850Y775590D02*
Y968503D01*
G01Y775590D02*
G03X925787Y771653I3937J0D01*
G01X984843D02*
X925787D01*
G01X929725Y779527D02*
Y886881D01*
G01Y779527D02*
X980906D01*
G01X929725D02*
Y886881D01*
G01Y779527D02*
X980906D01*
G01X929725Y886881D02*
G03X921851I-3937J1D01*
G01X929725D02*
G03X921851I-3937J1D01*
G01Y912079D02*
G03X929725I3937J-1D01*
G01X921851D02*
G03X929725I3937J-1D01*
G01Y912078D02*
Y968504D01*
G01Y912078D02*
Y968504D01*
G01X959606Y850829D02*
G03X951024I-4291J0D01*
G01D02*
G03X959606I4291J0D01*
G01X984201Y-7874D02*
G03Y0I0J3937D01*
G01Y-7874D02*
G03Y0I0J3937D01*
G01X984843Y771653D02*
G03X988780Y775590I0J3937D01*
G01X980907Y886881D02*
X980906Y779527D01*
G01X980907Y886881D02*
X980906Y779527D01*
G01X988781Y886881D02*
G03X980907I-3937J1D01*
G01X988781D02*
G03X980907I-3937J1D01*
G01Y912079D02*
G03X988781I3937J-1D01*
G01X980907D02*
G03X988781I3937J-1D01*
G01X980907D02*
X980906Y968504D01*
G01X980907Y912079D02*
X980906Y968504D01*
G01X1008465Y996063D02*
G03X980906Y968504I0J-27559D01*
G01X1008465Y996063D02*
G03X980906Y968504I0J-27559D01*
G01X1011417Y237795D02*
X1005118D01*
G02Y250394I0J6300D01*
G01X1011417D01*
G02Y237795I0J-6299D01*
G01Y405118D02*
X1005118D01*
G02Y417717I0J6300D01*
G01X1011417D01*
G02Y405118I0J-6299D01*
G01X988780Y968503D02*
Y775590D01*
G01X1008465Y988189D02*
G03X988780Y968503I0J-19685D01*
G01X1009398Y-7874D02*
X1108229D01*
G01X1009398Y0D02*
G03Y-7874I-1J-3937D01*
G01D02*
X1108229D01*
G01X1009398Y0D02*
G03Y-7874I-1J-3937D01*
G01X1380315Y988189D02*
X1008465D01*
G01X1070592Y996063D02*
X1008466D01*
G01X1070592D02*
X1008466D01*
G01X1070592Y988189D02*
G03Y996063I0J3937D01*
G01Y988189D02*
G03Y996063I0J3937D01*
G01X1095789D02*
G03Y988189I0J-3937D01*
G01Y996063D02*
G03Y988189I0J-3937D01*
G01X1325399Y996063D02*
X1095789D01*
G01X1325399D02*
X1095789D01*
G01X1112146Y3937D02*
Y210629D01*
G01X1108209Y0D02*
G03X1112146Y3937I0J3937D01*
G01X1108208Y-7874D02*
G03X1120020Y3938I1J11811D01*
G01X1108208Y-7874D02*
G03X1120020Y3938I1J11811D01*
G01Y99950D02*
G03X1112146I-3937J0D01*
G01X1120020D02*
G03X1112146I-3937J0D01*
G01Y125147D02*
G03X1120020I3937J0D01*
G01X1112146D02*
G03X1120020I3937J0D01*
G01X1116083Y214566D02*
X1194824D01*
G01X1116083D02*
G03X1112146Y210629I0J-3937D01*
G01X1120020Y99950D02*
Y3938D01*
G01Y99950D02*
Y3938D01*
G01Y125147D02*
Y206693D01*
G01Y125147D02*
Y206693D01*
G01X1120021D02*
X1190887D01*
G01X1120021D02*
X1190887D01*
G01X1161386Y128841D02*
G03X1152804I-4291J0D01*
G01D02*
G03X1161386I4291J0D01*
G01X1198760Y3937D02*
G03X1210571Y-7874I11811J0D01*
G01X1198760Y3937D02*
G03X1210571Y-7874I11811J0D01*
G01X1198761Y97100D02*
X1198760Y3937D01*
G01X1198761Y97100D02*
X1198760Y3937D01*
G01X1206635Y97100D02*
G03X1198761I-3937J0D01*
G01X1206635D02*
G03X1198761I-3937J0D01*
G01Y122297D02*
G03X1206635I3937J0D01*
G01X1198761D02*
G03X1206635I3937J0D01*
G01X1198761D02*
Y168002D01*
G01Y122297D02*
Y168002D01*
G01X1190887Y179134D02*
G03X1198761Y167998I11811J0D01*
G01X1190887Y179134D02*
G03X1198761Y167998I11811J0D01*
G01X1198760Y179133D02*
G03X1202697Y175196I3937J0D01*
G01X1198760Y210629D02*
Y179133D01*
G01X1190887Y206693D02*
Y179134D01*
G01Y206693D02*
Y179134D01*
G01X1198760Y210629D02*
G03X1194824Y214566I-3937J0D01*
G01X1210571Y0D02*
X1396063D01*
G01X1206634Y3937D02*
G03X1210571Y0I3937J0D01*
G01X1206634Y171259D02*
Y3937D01*
G01X1210552Y-7874D02*
X1210572D01*
G01D02*
G03Y0I0J3937D01*
G01X1210552Y-7874D02*
X1210572D01*
G01D02*
G03Y0I0J3937D01*
G01X1206634Y171259D02*
G03X1202697Y175196I-3937J0D01*
G01X1226320Y-7874D02*
X1380317D01*
G01X1226320Y0D02*
G03Y-7874I0J-3937D01*
G01D02*
X1380317D01*
G01X1226320Y0D02*
G03Y-7874I0J-3937D01*
G01X1230315Y149213D02*
X1224016D01*
G02Y161811I0J6299D01*
G01X1230315D01*
G02Y149213I0J-6299D01*
G01Y405118D02*
X1224016D01*
G02Y417717I0J6300D01*
G01X1230315D01*
G02Y405118I0J-6299D01*
G01X1354801Y996063D02*
X1325399D01*
G01X1354801D02*
X1325399D01*
G01Y1023622D02*
X1385001D01*
G01X1325399D02*
X1385001D01*
G01X1354801Y988189D02*
G03Y996063I0J3937D01*
G01Y988189D02*
G03Y996063I0J3937D01*
G01X1380316Y-7874D02*
G03Y0I0J3937D01*
G01Y-7874D02*
G03Y0I0J3937D01*
G01X1400000Y968503D02*
G03X1380315Y988189I-19685J1D01*
G01X1379998Y996063D02*
G03Y988189I0J-3937D01*
G01Y996063D02*
G03Y988189I0J-3937D01*
G01X1400001Y996063D02*
X1379998D01*
G01X1400001D02*
X1379998D01*
G01X1392127Y-25591D02*
G03X1400001Y-17717I0J7874D01*
G01X1392167Y-15015D02*
G03X1383585I-4291J0D01*
G01D02*
G03X1392167I4291J0D01*
G01X1392127Y-25591D02*
G03X1400001Y-17717I0J7874D01*
G01X1396063Y0D02*
G03X1400000Y3937I0J3937D01*
G01X1396064Y-7874D02*
X1400001D01*
G01X1396064Y0D02*
G03Y-7874I0J-3937D01*
G01D02*
X1400001D01*
G01X1396064Y0D02*
G03Y-7874I0J-3937D01*
G01X1380710Y1008622D02*
G03X1389292I4291J0D01*
G01D02*
G03X1380710I-4291J0D01*
G01X1400001D02*
G03X1385001Y1023622I-15000J0D01*
G01X1400001Y1008622D02*
G03X1385001Y1023622I-15000J0D01*
G01X1400001Y-17717D02*
Y-7874D01*
G01Y-17717D02*
Y-7874D01*
G01X1400000Y3937D02*
Y968503D01*
G01X1400001Y996063D02*
Y1008622D01*
G01Y996063D02*
Y1008622D01*
G54D12*
G01X362302Y164450D02*
G02X362904Y164201I0J-852D01*
G01X378181Y137704D02*
Y138359D01*
G01D02*
G03X378059Y138943I-1471J-3D01*
G01X379181Y137615D02*
X379345Y137779D01*
G01X376671Y133886D02*
G03X377256Y135300I-1414J1413D01*
G01D02*
Y136819D01*
G01D02*
G03X376902Y137674I-1209J0D01*
G01D02*
X376602Y137974D01*
G01D02*
G02X376175Y139005I1031J1031D01*
G01X378059Y138943D02*
G03X377750Y139400I-1352J-581D01*
G01X379345Y139500D02*
G03X378940Y140478I-1383J0D01*
G01D02*
X378923Y140495D01*
G01D02*
X378364Y141053D01*
G01D02*
G02X377757Y142520I1467J1466D01*
G01X376175Y139005D02*
Y140200D01*
G01D02*
G03X375643Y141483I-1815J-1D01*
G01D02*
X375578Y141549D01*
G01D02*
X374607Y142520D01*
G01X364311Y153517D02*
X366743D01*
G01D02*
X368333Y155107D01*
G01X362904Y164201D02*
X363871Y163234D01*
G01D02*
G03X364487Y162979I616J616D01*
G01D02*
X367242D01*
G01D02*
G03X367646Y163147I-1J572D01*
G01D02*
X368000Y163500D01*
G01D02*
G03X368325Y164285I-785J785D01*
G01D02*
Y164585D01*
G01X379181Y132221D02*
Y137615D01*
G01X379345Y137779D02*
Y139500D01*
G01X385219Y137309D02*
G03X385594Y138214I-905J905D01*
G01D02*
Y139415D01*
G01X395108Y138000D02*
Y139255D01*
G01X388780Y137460D02*
Y139250D01*
G01X385594Y139415D02*
G03X385163Y140455I-1470J0D01*
G01D02*
X384370Y141248D01*
G01D02*
G02X384056Y142006I758J758D01*
G01D02*
Y142520D01*
G01X395108Y139255D02*
G03X394560Y140578I-1871J0D01*
G01D02*
X393794Y141344D01*
G01D02*
G02X393505Y142042I698J698D01*
G01D02*
Y142520D01*
G01X388780Y139250D02*
G03X388232Y140573I-1871J0D01*
G01D02*
X387507Y141298D01*
G01D02*
G02X387206Y142025I727J727D01*
G01D02*
Y142520D01*
G01X398260Y138220D02*
Y139450D01*
G01X407958Y137961D02*
G02X407678Y138637I676J676D01*
G01D02*
Y139373D01*
G01X405129Y135183D02*
G02X404528Y136633I1449J1450D01*
G01D02*
Y139868D01*
G01X398260Y139450D02*
G03X398024Y140543I-2655J-1D01*
G01D02*
G03X397594Y141581I-1468J0D01*
G01D02*
X396655Y142520D01*
G01X407678Y139373D02*
G03X407217Y140486I-1574J0D01*
G01D02*
X407216Y140487D01*
G01D02*
X407215D01*
G01D02*
X406404Y141298D01*
G01D02*
G02X406103Y142025I727J727D01*
G01D02*
Y142520D01*
G01X404528Y139868D02*
G03X403765Y141709I-2604J-1D01*
G01D02*
X402954Y142520D01*
G54D13*
G01X353997Y83093D02*
X344778Y92312D01*
G01D02*
G02X343650Y95035I2722J2723D01*
G01D02*
Y99500D01*
G01D02*
G03X343049Y100951I-2052J0D01*
G01D02*
X342000Y102000D01*
G01X354953Y84047D02*
X345732Y93268D01*
G01D02*
G02X345000Y95036I1768J1768D01*
G01D02*
Y99586D01*
G01D02*
G02X346000Y102000I3414J0D01*
G01X363517Y81965D02*
X356720D01*
G01D02*
G02X353997Y83093I0J3850D01*
G01X363518Y83315D02*
X356721D01*
G01D02*
G02X354953Y84047I0J2500D01*
G01X409392Y37126D02*
X365285Y81233D01*
G01X410348Y38080D02*
X366241Y82187D01*
G01X365285Y81233D02*
G03X363517Y81965I-1768J-1768D01*
G01X366241Y82187D02*
G03X363518Y83315I-2723J-2722D01*
G01X373118Y92918D02*
X415110Y50926D01*
G01X374072Y93874D02*
X416066Y51880D01*
G01X366215Y90062D02*
X412251Y44026D01*
G01X367169Y91018D02*
X413207Y44980D01*
G01X371990Y113222D02*
Y95641D01*
G01D02*
G03X373118Y92918I3850J0D01*
G01X373340Y113221D02*
Y95642D01*
G01D02*
G03X374072Y93874I2500J0D01*
G01X365087Y113218D02*
Y92785D01*
G01D02*
G03X366215Y90062I3850J0D01*
G01X366437Y113218D02*
Y92786D01*
G01D02*
G03X367169Y91018I2500J0D01*
G01X378890Y115027D02*
Y98500D01*
G01D02*
G03X380018Y95777I3850J0D01*
G01X373540Y123400D02*
G02X374151Y121925I-1475J-1475D01*
G01D02*
Y118438D01*
G01D02*
G02X372796Y115167I-4626J0D01*
G01D02*
G03X371990Y113222I1946J-1946D01*
G01X376040Y123400D02*
G03X375501Y122099I1301J-1301D01*
G01D02*
Y118437D01*
G01D02*
G02X373751Y114212I-5976J0D01*
G01D02*
G03X373340Y113221I991J-992D01*
G01X367540Y123400D02*
G02X368115Y122012I-1388J-1388D01*
G01D02*
Y117966D01*
G01D02*
G02X367704Y116975I-1402J1D01*
G01D02*
X365893Y115164D01*
G01D02*
G03X365087Y113218I1946J-1946D01*
G01X370040Y123400D02*
G03X369465Y122012I1388J-1388D01*
G01D02*
Y117965D01*
G01D02*
G02X368659Y116020I-2752J1D01*
G01D02*
X366848Y114209D01*
G01D02*
G03X366437Y113218I991J-992D01*
G01X379500Y116500D02*
G03X378890Y115027I1473J-1473D01*
G01X373540Y125600D02*
G02X375299Y129848I6007J1D01*
G01D02*
X375841Y130389D01*
G01D02*
X376067Y130615D01*
G01D02*
X377520Y132067D01*
G01X376040Y125600D02*
Y127848D01*
G01D02*
G02X376626Y129263I2001J0D01*
G01D02*
X378896Y131533D01*
G01X367540Y125600D02*
G02X368294Y127420I2574J0D01*
G01D02*
X375756Y134882D01*
G01X370040Y125600D02*
Y125607D01*
G01D02*
G02X371206Y128422I3981J0D01*
G01D02*
X376656Y133872D01*
G01X380018Y95777D02*
X417969Y57826D01*
G01X380972Y96733D02*
X418925Y58780D01*
G01X380240Y115028D02*
Y98501D01*
G01D02*
G03X380972Y96733I2500J0D01*
G01X392690Y121500D02*
Y104218D01*
G01D02*
G03X393818Y101495I3850J0D01*
G01D02*
X423687Y71626D01*
G01X394040Y123400D02*
Y104219D01*
G01D02*
G03X394772Y102451I2500J0D01*
G01D02*
X424643Y72580D01*
G01X385790Y122943D02*
Y101359D01*
G01D02*
G03X386918Y98636I3850J0D01*
G01D02*
X420828Y64726D01*
G01X387140Y121227D02*
Y101360D01*
G01D02*
G03X387872Y99592I2500J0D01*
G01D02*
X421784Y65680D01*
G01X380229Y122504D02*
Y117500D01*
G01D02*
G02X380037Y117038I-654J1D01*
G01D02*
X379500Y116500D01*
G01X382040Y123400D02*
G03X381579Y122287I1113J-1113D01*
G01D02*
Y117499D01*
G01D02*
G02X380992Y116083I-2004J1D01*
G01D02*
X380456Y115545D01*
G01D02*
X380455D01*
G01D02*
G03X380241Y115027I518J-517D01*
G01D02*
X380240Y115028D01*
G01X392160Y122781D02*
G02X392690Y121500I-1281J-1280D01*
G01X388040Y123400D02*
G03X387140Y121227I2173J-2173D01*
G01X379540Y125600D02*
G03X380579Y128108I-2508J2508D01*
G01D02*
Y130383D01*
G01D02*
G02X381119Y131691I1850J2D01*
G01D02*
X382518Y133089D01*
G01D02*
G03X382929Y134080I-991J992D01*
G01D02*
Y137400D01*
G01D02*
G02X383552Y138904I2127J0D01*
G01D02*
X384019Y139371D01*
G01X379540Y123400D02*
X380083Y122857D01*
G01D02*
G02X380229Y122504I-354J-353D01*
G01X382040Y125600D02*
G02X381929Y125868I268J268D01*
G01D02*
Y130383D01*
G01D02*
G02X382075Y130736I500J0D01*
G01D02*
X383473Y132134D01*
G01D02*
G03X384279Y134080I-1946J1946D01*
G01D02*
Y135494D01*
G01D02*
G02X384287Y135679I2112J1D01*
G01D02*
Y135680D01*
G01D02*
G02X384356Y136060I2104J-186D01*
G01D02*
G02X384465Y136361I2035J-567D01*
G01D02*
G02X384515Y136465I1928J-863D01*
G01D02*
G02X384540Y136513I1886J-952D01*
G01D02*
G02X384558Y136544I1836J-1045D01*
G01D02*
G02X384573Y136569I1819J-1074D01*
G01D02*
G02X384664Y136710I1819J-1074D01*
G01D02*
G02X384665Y136712I1890J-944D01*
G01D02*
G02X384701Y136762I1732J-1209D01*
G01D02*
G02X384713Y136777I1655J-1312D01*
G01D02*
G02X384855Y136944I1678J-1283D01*
G01D02*
G02X384898Y136988I1532J-1454D01*
G01D02*
X385219Y137309D01*
G01X391540Y125600D02*
X392566Y126626D01*
G01D02*
G03X392899Y127124I-1087J1087D01*
G01D02*
G02X393233Y127624I1420J-587D01*
G01D02*
X393721Y128112D01*
G01D02*
G03X393915Y128578I-464J467D01*
G01D02*
Y129694D01*
G01D02*
X393904Y129705D01*
G01D02*
G02X393758Y130058I354J353D01*
G01D02*
Y138741D01*
G01D02*
G03X393510Y139340I-847J0D01*
G01X391540Y123400D02*
X392160Y122781D01*
G01X394040Y125600D02*
Y126115D01*
G01D02*
G02X394327Y126808I980J0D01*
G01D02*
X394676Y127157D01*
G01D02*
G03X395265Y128578I-1420J1421D01*
G01D02*
Y130200D01*
G01D02*
G02X395108Y130579I379J379D01*
G01D02*
Y138000D01*
G01X385540Y125600D02*
G03X385929Y126539I-939J939D01*
G01D02*
Y135177D01*
G01D02*
G02X386527Y136622I2043J1D01*
G01D02*
X387173Y137268D01*
G01D02*
Y139376D01*
G01X385540Y123400D02*
X385644Y123296D01*
G01D02*
G02X385790Y122943I-354J-353D01*
G01X388040Y125600D02*
X387621Y126019D01*
G01D02*
G02X387279Y126845I826J826D01*
G01D02*
Y135177D01*
G01D02*
G02X387482Y135667I693J0D01*
G01D02*
X388523Y136708D01*
G01D02*
Y137203D01*
G01D02*
X388780Y137460D01*
G01X412115Y35998D02*
G02X409392Y37126I0J3850D01*
G01X412116Y37348D02*
G02X410348Y38080I0J2500D01*
G01X399590Y107077D02*
G03X400718Y104354I3850J0D01*
G01D02*
X426546Y78526D01*
G01X400940Y107078D02*
G03X401672Y105310I2500J0D01*
G01D02*
X427502Y79480D01*
G01X407915Y106916D02*
X429403Y85428D01*
G01X408870Y107871D02*
X430359Y86382D01*
G01X398190Y122412D02*
Y116302D01*
G01D02*
G03X398841Y114729I2224J-1D01*
G01D02*
X399349Y114221D01*
G01D02*
G02X399590Y113640I-580J-581D01*
G01D02*
Y107077D01*
G01X399540Y122668D02*
Y116302D01*
G01D02*
G03X399796Y115684I874J0D01*
G01D02*
X400304Y115176D01*
G01D02*
G02X400940Y113641I-1535J-1535D01*
G01D02*
Y107078D01*
G01X409540Y123400D02*
G02X410505Y121812I-2777J-2775D01*
G01D02*
G02X410690Y120624I-3741J-1191D01*
G01D02*
Y117641D01*
G01D02*
G03X411496Y115695I2752J0D01*
G01D02*
X412979Y114212D01*
G01X412040Y123400D02*
Y117641D01*
G01D02*
G03X412451Y116650I1402J1D01*
G01X404040Y122499D02*
Y117845D01*
G01D02*
G03X405167Y115124I3849J0D01*
G01D02*
X405357Y114934D01*
G01D02*
G02X406490Y112200I-2734J-2735D01*
G01D02*
Y110358D01*
G01D02*
G03X407915Y106916I4867J-1D01*
G01X406040Y123400D02*
G03X405390Y121831I1569J-1569D01*
G01D02*
Y117846D01*
G01D02*
G03X406122Y116079I2499J0D01*
G01D02*
X406312Y115889D01*
G01D02*
G02X407840Y112201I-3689J-3689D01*
G01D02*
Y110358D01*
G01D02*
G03X408870Y107871I3517J0D01*
G01X397540Y125667D02*
G03X398540Y128081I-2414J2414D01*
G01D02*
Y130120D01*
G01D02*
G03X398129Y131111I-1402J-1D01*
G01D02*
X397461Y131779D01*
G01D02*
G02X396655Y133724I1946J1946D01*
G01D02*
Y137094D01*
G01D02*
G03X396607Y137306I-499J-2D01*
G01D02*
G03X396606Y137308I-447J-222D01*
G01D02*
G03X396507Y137449I-452J-212D01*
G01D02*
X396175Y137781D01*
G01D02*
Y138854D01*
G01D02*
X396683Y139362D01*
G01X397540Y123467D02*
X397903Y123104D01*
G01D02*
G02X398190Y122412I-691J-692D01*
G01X400040Y123467D02*
X399752Y123179D01*
G01D02*
G03X399540Y122668I510J-511D01*
G01X400040Y125667D02*
G02X399890Y126007I362J363D01*
G01D02*
G02Y126029I512J11D01*
G01D02*
Y130120D01*
G01D02*
G03X399084Y132066I-2752J0D01*
G01D02*
X398416Y132734D01*
G01D02*
G02X398005Y133725I991J992D01*
G01D02*
Y137965D01*
G01D02*
G03X398260Y138220I0J255D01*
G01X409540Y125600D02*
G03X410040Y126807I-1207J1207D01*
G01D02*
Y132801D01*
G01D02*
G03X409269Y134660I-2631J-2D01*
G01D02*
X406871Y137058D01*
G01D02*
X406729Y137399D01*
G01D02*
X406728Y137401D01*
G01D02*
X406474Y137655D01*
G01D02*
G02X406328Y138008I354J353D01*
G01D02*
Y138939D01*
G01X412040Y125600D02*
G02X411390Y127169I1569J1569D01*
G01D02*
Y132800D01*
G01D02*
G03X410224Y135615I-3981J0D01*
G01D02*
X408015Y137824D01*
G01D02*
X407958Y137961D01*
G01X403540Y125600D02*
G03X404625Y128219I-2619J2619D01*
G01D02*
Y133605D01*
G01D02*
G03X404624Y133623I-335J-10D01*
G01D02*
G03X404527Y133842I-335J-17D01*
G01D02*
X404428Y133941D01*
G01D02*
Y133974D01*
G01D02*
X403652Y134750D01*
G01D02*
G02X402953Y136437I1686J1687D01*
G01D02*
Y139370D01*
G01X403540Y123400D02*
X403822Y123118D01*
G01D02*
X404001Y122693D01*
G01D02*
G02X404010Y122668I-465J-182D01*
G01D02*
G02X404040Y122499I-470J-171D01*
G01X406040Y125600D02*
G02X405975Y125757I157J157D01*
G01D02*
Y134058D01*
G01D02*
G03X405778Y134534I-673J0D01*
G01D02*
X405129Y135183D01*
G01X406328Y138939D02*
G03X406319Y139026I-499J-8D01*
G01D02*
G03X406313Y139050I-486J-109D01*
G01D02*
G03X406299Y139103I-488J-101D01*
G01D02*
G03X406182Y139291I-472J-163D01*
G01D02*
X406143Y139329D01*
G01D02*
X406103Y139371D01*
G01X439056Y35998D02*
X412115D01*
G01X439057Y37348D02*
X412116D01*
G01X415110Y50926D02*
G03X417833Y49798I2723J2722D01*
G01D02*
X445256D01*
G01X416066Y51880D02*
G03X417834Y51148I1768J1768D01*
G01D02*
X445257D01*
G01X412251Y44026D02*
G03X414974Y42898I2723J2722D01*
G01D02*
X442397D01*
G01X413207Y44980D02*
G03X414975Y44248I1768J1768D01*
G01D02*
X442398D01*
G01X417969Y57826D02*
G03X420692Y56698I2723J2722D01*
G01D02*
X448766D01*
G01X418925Y58780D02*
G03X420693Y58048I1768J1768D01*
G01D02*
X448767D01*
G01X423687Y71626D02*
G03X426410Y70498I2723J2722D01*
G01D02*
X457556D01*
G01X424643Y72580D02*
G03X426411Y71848I1768J1768D01*
G01D02*
X457557D01*
G01X420828Y64726D02*
G03X423551Y63598I2723J2722D01*
G01D02*
X454456D01*
G01X421784Y65680D02*
G03X423552Y64948I1768J1768D01*
G01D02*
X454457D01*
G01X426546Y78526D02*
G03X429269Y77398I2723J2722D01*
G01X427502Y79480D02*
G03X429270Y78748I1768J1768D01*
G01X414295Y110295D02*
X432262Y92328D01*
G01X415250Y111250D02*
X433218Y93282D01*
G01X412979Y114212D02*
G02X413390Y113221I-991J-992D01*
G01D02*
Y112480D01*
G01D02*
G03X414295Y110295I3091J0D01*
G01X412451Y116650D02*
X413934Y115167D01*
G01D02*
G02X414740Y113222I-1946J-1946D01*
G01D02*
Y112481D01*
G01D02*
G03X415250Y111250I1741J0D01*
G01X456462Y19628D02*
X440824Y35266D01*
G01D02*
G03X439056Y35998I-1768J-1768D01*
G01X457418Y20582D02*
X441780Y36220D01*
G01D02*
G03X439057Y37348I-2723J-2722D01*
G01X442397Y42898D02*
G02X444165Y42166I0J-2500D01*
G01D02*
X459703Y26628D01*
G01X442398Y44248D02*
G02X445121Y43120I0J-3850D01*
G01X429269Y77398D02*
X464156D01*
G01X429270Y78748D02*
X464157D01*
G01X429403Y85428D02*
G03X432126Y84300I2723J2722D01*
G01D02*
X469850D01*
G01X430359Y86382D02*
G03X432127Y85650I1768J1768D01*
G01D02*
X469850D01*
G01X432262Y92328D02*
G03X434985Y91200I2723J2722D01*
G01D02*
X466444D01*
G01X433218Y93282D02*
G03X434986Y92550I1768J1768D01*
G01D02*
X466443D01*
G01X515283Y18500D02*
X459185D01*
G01D02*
G02X456462Y19628I0J3850D01*
G01X515282Y19850D02*
X459186D01*
G01D02*
G02X457418Y20582I0J2500D01*
G01X447024Y49066D02*
X462262Y33828D01*
G01X447980Y50020D02*
X463218Y34782D01*
G01X459703Y26628D02*
G03X462426Y25500I2723J2722D01*
G01X445121Y43120D02*
X460659Y27582D01*
G01D02*
G03X462427Y26850I1768J1768D01*
G01X445256Y49798D02*
G02X447024Y49066I0J-2500D01*
G01X445257Y51148D02*
G02X447980Y50020I0J-3850D01*
G01X448766Y56698D02*
G02X450534Y55966I0J-2500D01*
G01D02*
X465772Y40728D01*
G01X451490Y56920D02*
X466728Y41682D01*
G01X448767Y58048D02*
G02X451490Y56920I0J-3850D01*
G01X457556Y70498D02*
G02X459324Y69766I0J-2500D01*
G01D02*
X474462Y54628D01*
G01X457557Y71848D02*
G02X460280Y70720I0J-3850D01*
G01D02*
X475418Y55582D01*
G01X454456Y63598D02*
G02X456224Y62866I0J-2500D01*
G01D02*
X471462Y47628D01*
G01X454457Y64948D02*
G02X457180Y63820I0J-3850D01*
G01D02*
X472418Y48582D01*
G01X462262Y33828D02*
G03X464985Y32700I2723J2722D01*
G01D02*
X509965D01*
G01X463218Y34782D02*
G03X464986Y34050I1768J1768D01*
G01D02*
X509964D01*
G01X462426Y25500D02*
X512524D01*
G01X462427Y26850D02*
X512523D01*
G01X465772Y40728D02*
G03X468495Y39600I2723J2722D01*
G01D02*
X506965D01*
G01X466728Y41682D02*
G03X468496Y40950I1768J1768D01*
G01D02*
X506964D01*
G01X474462Y54628D02*
G03X477185Y53500I2723J2722D01*
G01D02*
X501074D01*
G01X475418Y55582D02*
G03X477186Y54850I1768J1768D01*
G01D02*
X501073D01*
G01X471462Y47628D02*
G03X474185Y46500I2723J2722D01*
G01D02*
X503833D01*
G01X472418Y48582D02*
G03X474186Y47850I1768J1768D01*
G01D02*
X503832D01*
G01X465924Y76666D02*
X480962Y61628D01*
G01X466880Y77620D02*
X481918Y62582D01*
G01X464156Y77398D02*
G02X465924Y76666I0J-2500D01*
G01X464157Y78748D02*
G02X466880Y77620I0J-3850D01*
G01X469850Y84300D02*
G03X471795Y85106I-1J2752D01*
G01D02*
X481344Y94655D01*
G01X469850Y85650D02*
G03X470840Y86061I-2J1402D01*
G01D02*
X480389Y95610D01*
G01X466444Y91200D02*
G03X469167Y92328I0J3850D01*
G01D02*
X479028Y102189D01*
G01X466443Y92550D02*
G03X468211Y93282I0J2500D01*
G01D02*
X478073Y103144D01*
G01X480962Y61628D02*
G03X483685Y60500I2723J2722D01*
G01D02*
X498315D01*
G01X481918Y62582D02*
G03X483686Y61850I1768J1768D01*
G01D02*
X498314D01*
G01X479028Y102189D02*
G02X486901Y105450I7873J-7873D01*
G01D02*
X515300D01*
G01X478073Y103144D02*
G02X486900Y106800I8827J-8828D01*
G01X481344Y94655D02*
G02X488695Y97700I7351J-7351D01*
G01D02*
X524200D01*
G01X480389Y95610D02*
G02X488694Y99050I8305J-8306D01*
G01D02*
X524200D01*
G01X486900Y106800D02*
X515300D01*
G01X509965Y32700D02*
G03X512688Y33828I0J3850D01*
G01X509964Y34050D02*
G03X511732Y34782I0J2500D01*
G01X506965Y39600D02*
G03X509688Y40728I0J3850D01*
G01D02*
X591378Y122418D01*
G01X506964Y40950D02*
G03X508732Y41682I0J2500D01*
G01D02*
X590422Y123372D01*
G01X501074Y53500D02*
G03X503797Y54628I0J3850D01*
G01D02*
X585387Y136218D01*
G01X501073Y54850D02*
G03X502841Y55582I0J2500D01*
G01D02*
X584431Y137172D01*
G01X503833Y46500D02*
G03X506556Y47628I0J3850D01*
G01D02*
X588246Y129318D01*
G01X503832Y47850D02*
G03X505600Y48582I0J2500D01*
G01D02*
X587290Y130272D01*
G01X498315Y60500D02*
G03X501038Y61628I0J3850D01*
G01D02*
X582528Y143118D01*
G01X498314Y61850D02*
G03X500082Y62582I0J2500D01*
G01D02*
X581572Y144072D01*
G01X600096Y101718D02*
X518006Y19628D01*
G01D02*
G02X515283Y18500I-2723J2722D01*
G01X599140Y102672D02*
X517050Y20582D01*
G01D02*
G02X515282Y19850I-1768J1768D01*
G01X512688Y33828D02*
X594378Y115518D01*
G01X511732Y34782D02*
X593422Y116472D01*
G01X512524Y25500D02*
G03X515247Y26628I0J3850D01*
G01D02*
X597237Y108618D01*
G01X512523Y26850D02*
G03X514291Y27582I0J2500D01*
G01D02*
X596281Y109572D01*
G01X515300Y105450D02*
G03X528278Y110825I1J18354D01*
G01X524200Y97700D02*
G03X526607Y98697I0J3404D01*
G01D02*
X582928Y155018D01*
G01X524200Y99050D02*
G03X525652Y99652I-1J2054D01*
G01D02*
X581972Y155972D01*
G01X515300Y106800D02*
G03X527323Y111780I0J17003D01*
G01X528278Y110825D02*
X579371Y161918D01*
G01X527323Y111780D02*
X578415Y162872D01*
G01X591378Y122418D02*
G02X593146Y123150I1768J-1768D01*
G01X590422Y123372D02*
G02X593145Y124500I2723J-2722D01*
G01X585387Y136218D02*
G02X587155Y136950I1768J-1768D01*
G01D02*
X605638D01*
G01X584431Y137172D02*
G02X587154Y138300I2723J-2722D01*
G01D02*
X605637D01*
G01X588246Y129318D02*
G02X590014Y130050I1768J-1768D01*
G01D02*
X608497D01*
G01X587290Y130272D02*
G02X590013Y131400I2723J-2722D01*
G01D02*
X608496D01*
G01X582528Y143118D02*
G02X584296Y143850I1768J-1768D01*
G01D02*
X602006D01*
G01X581572Y144072D02*
G02X584295Y145200I2723J-2722D01*
G01D02*
X602005D01*
G01X582928Y155018D02*
G02X584696Y155750I1768J-1768D01*
G01X579371Y161918D02*
G02X581139Y162650I1768J-1768D01*
G01D02*
X600909D01*
G01X578415Y162872D02*
G02X581138Y164000I2723J-2722D01*
G01D02*
X600910D01*
G01X584696Y155750D02*
X603770D01*
G01X581972Y155972D02*
G02X584695Y157100I2723J-2722D01*
G01D02*
X603769D01*
G01X607933Y70118D02*
Y70079D01*
G01D02*
X610730Y67282D01*
G01X610148Y80118D02*
X608598Y81668D01*
G01D02*
Y84598D01*
G01D02*
X613000Y89000D01*
G01X603897Y80118D02*
X605766D01*
G01D02*
X607082Y80918D01*
G01D02*
Y85082D01*
G01D02*
X611500Y89500D01*
G01X622059Y102450D02*
X601864D01*
G01D02*
G03X600096Y101718I0J-2500D01*
G01X622058Y103800D02*
X601863D01*
G01D02*
G03X599140Y102672I0J-3850D01*
G01X594378Y115518D02*
G02X596146Y116250I1768J-1768D01*
G01D02*
X615673D01*
G01X593422Y116472D02*
G02X596145Y117600I2723J-2722D01*
G01D02*
X615672D01*
G01X597237Y108618D02*
G02X599005Y109350I1768J-1768D01*
G01D02*
X619202D01*
G01X596281Y109572D02*
G02X599004Y110700I2723J-2722D01*
G01D02*
X619201D01*
G01X593146Y123150D02*
X611356D01*
G01X593145Y124500D02*
X611355D01*
G01X605638Y136950D02*
G03X608361Y138078I0J3850D01*
G01D02*
X674460Y204177D01*
G01X605637Y138300D02*
G03X607405Y139032I0J2500D01*
G01X608497Y130050D02*
G03X611220Y131178I0J3850D01*
G01X608496Y131400D02*
G03X610264Y132132I0J2500D01*
G01X607405Y139032D02*
X673506Y205133D01*
G01X602006Y143850D02*
G03X604729Y144978I0J3850D01*
G01D02*
X657875Y198124D01*
G01X602005Y145200D02*
G03X603773Y145932I0J2500D01*
G01D02*
X656920Y199079D01*
G01X600909Y162650D02*
G03X603633Y163777I2J3850D01*
G01D02*
X627428Y187572D01*
G01X600910Y164000D02*
G03X602678Y164732I0J2500D01*
G01D02*
X626473Y188527D01*
G01X603770Y155750D02*
G03X606493Y156878I0J3850D01*
G01D02*
X642557Y192942D01*
G01X603769Y157100D02*
G03X605537Y157832I0J2500D01*
G01D02*
X641602Y193897D01*
G01X610730Y67282D02*
G02X611215Y66111I-1171J-1171D01*
G01D02*
Y63700D01*
G01D02*
G03X614765Y60150I3550J0D01*
G01D02*
X639748D01*
G01X615925Y70118D02*
X615886D01*
G01D02*
X613058Y67290D01*
G01D02*
G03X612565Y66100I1190J-1190D01*
G01D02*
Y63700D01*
G01D02*
G03X614765Y61500I2200J0D01*
G01D02*
X621310D01*
G01D02*
G03X622100Y61895I-1J990D01*
G01D02*
G02X622890Y62290I791J-595D01*
G01D02*
X624540D01*
G01D02*
G02X625330Y61895I-1J-990D01*
G01D02*
G03X626120Y61500I791J595D01*
G01X611889Y80118D02*
X610148D01*
G01X613000Y89000D02*
X644000D01*
G01X611500Y89500D02*
X611590D01*
G01D02*
X612440Y90350D01*
G01D02*
X643440D01*
G01X777621Y256417D02*
X624782Y103578D01*
G01D02*
G02X622059Y102450I-2723J2722D01*
G01X776666Y257372D02*
X623826Y104532D01*
G01D02*
G02X622058Y103800I-1768J1768D01*
G01X615673Y116250D02*
G03X618396Y117378I0J3850D01*
G01D02*
X784055Y283037D01*
G01X615672Y117600D02*
G03X617440Y118332I0J2500D01*
G01D02*
X783100Y283992D01*
G01X619202Y109350D02*
G03X621923Y110478I-2J3850D01*
G01D02*
X775277Y263832D01*
G01X619201Y110700D02*
G03X620968Y111433I-1J2500D01*
G01D02*
X774322Y264787D01*
G01X611356Y123150D02*
G03X614079Y124278I0J3850D01*
G01D02*
X769015Y279214D01*
G01X611355Y124500D02*
G03X613123Y125232I0J2500D01*
G01D02*
X768061Y280170D01*
G01X611220Y131178D02*
X753407Y273365D01*
G01X610264Y132132D02*
X752453Y274321D01*
G01X627065Y292277D02*
G03X625342Y294000I-1723J0D01*
G01D02*
X625000D01*
G01D02*
G03X624147Y293646I1J-1207D01*
G01D02*
X623500Y293000D01*
G01D02*
G03Y290674I1163J-1163D01*
G01D02*
X623819Y290355D01*
G01X615944Y315945D02*
X617367Y313104D01*
G01D02*
G02X617122Y312366I-492J-246D01*
G01D02*
X617121D01*
G01D02*
X617119Y312365D01*
G01D02*
Y312366D01*
G01D02*
G03X617117Y312363I1373J-917D01*
G01D02*
X616455Y312032D01*
G01D02*
G03X615200Y309266I2423J-2767D01*
G01D02*
Y304890D01*
G01D02*
G02X614916Y304203I-971J-1D01*
G01D02*
X613962Y303250D01*
G01X619884Y308070D02*
Y309734D01*
G01D02*
G03X618462Y311156I-1422J0D01*
G01D02*
X617823D01*
G01D02*
G03X617232Y310911I0J-836D01*
G01D02*
G03X616550Y309265I1646J-1646D01*
G01D02*
Y304890D01*
G01D02*
G03X616806Y304272I874J0D01*
G01D02*
X617828Y303250D01*
G01X639748Y60150D02*
Y60149D01*
G01D02*
G03X643421Y61672I0J5190D01*
G01X626120Y61500D02*
X627770D01*
G01D02*
G03X628560Y61895I-1J990D01*
G01D02*
G02X629350Y62290I791J-595D01*
G01D02*
X631000D01*
G01D02*
G02X631790Y61895I-1J-990D01*
G01D02*
G03X632580Y61500I791J595D01*
G01D02*
X639748D01*
G01D02*
G03X642463Y62624I1J3839D01*
G01X627428Y187572D02*
G03X628415Y189955I-2384J2383D01*
G01D02*
Y292277D01*
G01X626473Y188527D02*
G03X627065Y189956I-1429J1429D01*
G01D02*
Y292277D01*
G01X641602Y193897D02*
G03X642832Y196868I-2972J2970D01*
G01X628415Y292277D02*
G03X627440Y294523I-3073J1D01*
G01D02*
G02X627384Y297860I1585J1696D01*
G01D02*
X627754Y298230D01*
G01X642833Y292627D02*
G03X641460Y294000I-1373J0D01*
G01D02*
X641000D01*
G01D02*
G03X640147Y293646I1J-1207D01*
G01D02*
X639500Y293000D01*
G01D02*
G03Y290424I1288J-1288D01*
G01D02*
X639569Y290355D01*
G01X631694Y315945D02*
X633114Y313105D01*
G01D02*
G02X632868Y312367I-492J-246D01*
G01D02*
X632865Y312365D01*
G01D02*
X632375Y312120D01*
G01D02*
X632202Y312033D01*
G01D02*
G03X632024Y311867I2353J-2702D01*
G01D02*
G03X630975Y309332I2534J-2533D01*
G01D02*
Y305360D01*
G01D02*
G02X630376Y303914I-2045J0D01*
G01D02*
X629712Y303250D01*
G01X635629Y308070D02*
Y309614D01*
G01D02*
G03X635055Y311000I-1960J0D01*
G01D02*
G03X633618Y311232I-879J-880D01*
G01D02*
X632979Y310912D01*
G01D02*
G03X632325Y309333I1579J-1579D01*
G01D02*
Y305360D01*
G01D02*
G03X632931Y303897I2069J0D01*
G01D02*
X633578Y303250D01*
G01X643421Y61672D02*
X643504Y61756D01*
G01D02*
X648586Y66837D01*
G01D02*
X650140Y68391D01*
G01D02*
G03X650179Y68430I-1635J1674D01*
G01D02*
X669848Y88100D01*
G01X642463Y62624D02*
X642543Y62705D01*
G01D02*
X644616Y64778D01*
G01D02*
G03X644895Y65616I-701J699D01*
G01D02*
G02X645175Y66454I980J138D01*
G01D02*
X646341Y67621D01*
G01D02*
G02X647179Y67900I699J-701D01*
G01D02*
X647500D01*
G01D02*
X647857Y68019D01*
G01D02*
X649184Y69346D01*
G01D02*
G03X649463Y70184I-701J699D01*
G01D02*
G02X649743Y71022I980J138D01*
G01D02*
X650909Y72188D01*
G01D02*
G02X651747Y72468I700J-700D01*
G01D02*
G03X652585Y72747I139J980D01*
G01D02*
X653752Y73914D01*
G01X644000Y89000D02*
X662650Y107650D01*
G01X653752Y73914D02*
G03X654031Y74752I-701J699D01*
G01D02*
G02X654310Y75590I981J139D01*
G01D02*
X655477Y76756D01*
G01D02*
G02X656315Y77036I700J-700D01*
G01D02*
G03X657153Y77315I139J980D01*
G01D02*
X658320Y78482D01*
G01X643440Y90350D02*
X662090Y109000D01*
G01X657875Y198124D02*
G03X659976Y203196I-5072J5072D01*
G01X656920Y199079D02*
G03X658626Y203197I-4117J4118D01*
G01X642557Y192942D02*
G03X644183Y196868I-3926J3926D01*
G01D02*
Y292627D01*
G01X642832Y196868D02*
X642833Y196867D01*
G01D02*
Y292627D01*
G01X658626Y291989D02*
G03X658000Y293500I-2137J0D01*
G01D02*
G03X655500I-1250J-1250D01*
G01D02*
X655000Y293000D01*
G01D02*
G03Y290669I1166J-1166D01*
G01D02*
X655314Y290355D01*
G01X644183Y292627D02*
G03X643325Y294612I-2723J1D01*
G01D02*
G02X643273Y297999I1616J1719D01*
G01D02*
X643504Y298230D01*
G01X647439Y315945D02*
X648862Y313104D01*
G01D02*
G02X648617Y312366I-492J-246D01*
G01D02*
X648616D01*
G01D02*
X648614Y312365D01*
G01D02*
Y312366D01*
G01D02*
G03X648612Y312363I1373J-917D01*
G01D02*
X647950Y312032D01*
G01D02*
G03X646695Y309266I2423J-2767D01*
G01D02*
Y304890D01*
G01D02*
G02X646411Y304203I-971J-1D01*
G01D02*
X645457Y303250D01*
G01X651379Y308070D02*
Y309734D01*
G01D02*
G03X649957Y311156I-1422J0D01*
G01D02*
X649318D01*
G01D02*
G03X648727Y310911I0J-836D01*
G01D02*
G03X648045Y309265I1646J-1646D01*
G01D02*
Y304890D01*
G01D02*
G03X648301Y304272I874J0D01*
G01D02*
X649323Y303250D01*
G01X669848Y88100D02*
G02X672021Y89000I2173J-2173D01*
G01D02*
X684125D01*
G01X658320Y78482D02*
G03X658599Y79320I-701J699D01*
G01D02*
G02X658878Y80158I980J139D01*
G01D02*
X660045Y81324D01*
G01D02*
G02X660883Y81604I700J-700D01*
G01D02*
G03X661721Y81883I139J980D01*
G01D02*
X664129Y84291D01*
G01D02*
G03X664408Y85129I-701J699D01*
G01D02*
G02X664688Y85967I980J138D01*
G01D02*
X665854Y87134D01*
G01D02*
G02X666692Y87413I699J-701D01*
G01D02*
G03X667530Y87692I139J980D01*
G01D02*
X668893Y89055D01*
G01D02*
G02X672021Y90350I3127J-3128D01*
G01X674948Y101709D02*
G02X674358Y102299I0J590D01*
G01D02*
Y103170D01*
G01X676833Y100359D02*
G03X674469Y99380I0J-3343D01*
G01X672021Y90350D02*
X676563D01*
G01X662650Y107650D02*
X667427D01*
G01D02*
G02X668233Y107316I0J-1140D01*
G01D02*
G02X668283Y107255I-740J-658D01*
G01D02*
G03X669073Y106860I791J595D01*
G01D02*
X670723D01*
G01D02*
G03X671513Y107255I-1J990D01*
G01D02*
G02X671563Y107316I790J-596D01*
G01D02*
G02X672303Y107650I741J-656D01*
G01D02*
X677076D01*
G01X662090Y109000D02*
X687403D01*
G01X674460Y204177D02*
G03X675588Y206900I-2722J2723D01*
G01X659976Y203196D02*
Y296487D01*
G01X658626Y203197D02*
Y291989D01*
G01X673506Y205133D02*
G03X674238Y206901I-1768J1768D01*
G01D02*
Y292000D01*
G01X674736Y294171D02*
G02X674808Y298039I2043J1897D01*
G01D02*
X674999Y298230D01*
G01X674238Y292000D02*
G03X673699Y293301I-1840J0D01*
G01D02*
X673309Y293691D01*
G01D02*
G03X671191I-1059J-1059D01*
G01D02*
X670802Y293302D01*
G01D02*
G03Y290617I1342J-1343D01*
G01D02*
X671064Y290355D01*
G01X659976Y296487D02*
G03X659254Y298230I-2465J0D01*
G01X663189Y315945D02*
X664612Y313104D01*
G01D02*
G02X664367Y312366I-492J-246D01*
G01D02*
X664366D01*
G01D02*
X664364Y312365D01*
G01D02*
Y312366D01*
G01D02*
G03X664362Y312363I1373J-917D01*
G01D02*
X663700Y312032D01*
G01D02*
G03X662445Y309266I2423J-2767D01*
G01D02*
Y304890D01*
G01D02*
G02X662161Y304203I-971J-1D01*
G01D02*
X661207Y303250D01*
G01X667124Y308070D02*
Y309739D01*
G01D02*
G03X665707Y311156I-1417J0D01*
G01D02*
X665068D01*
G01D02*
G03X664477Y310911I0J-836D01*
G01D02*
G03X663795Y309265I1646J-1646D01*
G01D02*
Y304890D01*
G01D02*
G03X664051Y304272I874J0D01*
G01D02*
X665073Y303250D01*
G01X684125Y89000D02*
G03X687748Y90500I1J5123D01*
G01X688743Y107095D02*
G02X689398Y105514I-1581J-1581D01*
G01D02*
Y103062D01*
G01D02*
G02X689043Y102205I-1212J0D01*
G01D02*
G02X687846Y101709I-1197J1197D01*
G01D02*
X674948D01*
G01X689698Y108050D02*
G02X690748Y105515I-2536J-2535D01*
G01D02*
Y103061D01*
G01D02*
G02X689998Y101250I-2562J0D01*
G01D02*
G02X687847Y100359I-2152J2152D01*
G01D02*
X676833D01*
G01X687748Y90500D02*
X694348Y97100D01*
G01X676563Y90350D02*
G03X677353Y90745I-1J990D01*
G01D02*
G02X678143Y91140I791J-595D01*
G01D02*
X679793D01*
G01D02*
G02X680583Y90745I-1J-990D01*
G01D02*
G03X681373Y90350I791J595D01*
G01D02*
X684125D01*
G01D02*
G03X686793Y91455I0J3773D01*
G01D02*
X693393Y98055D01*
G01X677076Y107650D02*
G02X677866Y107255I-1J-990D01*
G01D02*
G03X678656Y106860I791J595D01*
G01D02*
X680306D01*
G01D02*
G03X681096Y107255I-1J990D01*
G01D02*
G02X681886Y107650I791J-595D01*
G01D02*
X687403D01*
G01D02*
G02X688743Y107095I0J-1895D01*
G01X687403Y109000D02*
G02X689698Y108050I1J-3245D01*
G01X694348Y122400D02*
X686248Y130500D01*
G01D02*
G02X685898Y131345I845J845D01*
G01D02*
Y133380D01*
G01X691315Y123523D02*
G03X690477Y123803I-700J-701D01*
G01D02*
G02X689639Y124082I-139J980D01*
G01D02*
X688472Y125249D01*
G01D02*
G02X688193Y126087I701J699D01*
G01D02*
G03X687914Y126924I-980J138D01*
G01D02*
X684806Y130032D01*
G01D02*
G03X682470I-1168J-1168D01*
G01D02*
X682418Y129980D01*
G01X675588Y206900D02*
Y292000D01*
G01D02*
G03X674736Y294171I-3190J1D01*
G01X694348Y97100D02*
G03X695748Y100480I-3381J3380D01*
G01D02*
Y119020D01*
G01X693393Y98055D02*
G03X694398Y100481I-2426J2426D01*
G01D02*
Y119019D01*
G01X695748Y119020D02*
G03X694348Y122400I-4781J0D01*
G01X694398Y119019D02*
G03X693393Y121445I-3431J0D01*
G01D02*
X691315Y123523D01*
G01X753407Y273365D02*
G03X754535Y276088I-2722J2723D01*
G01D02*
Y293000D01*
G01X752453Y274321D02*
G03X753185Y276089I-1768J1768D01*
G01D02*
Y290733D01*
G01X754535Y293000D02*
G03X753853Y294648I-2330J1D01*
G01D02*
X753463Y295037D01*
G01D02*
G02Y297954I1459J1458D01*
G01D02*
X753739Y298230D01*
G01X753185Y290733D02*
G03X752420Y292580I-2612J0D01*
G01D02*
X752000Y293000D01*
G01D02*
G03X749500I-1250J-1250D01*
G01D02*
G03Y290659I1171J-1171D01*
G01D02*
X749804Y290355D01*
G01X756935Y304890D02*
G02X756651Y304203I-971J-1D01*
G01D02*
X755697Y303250D01*
G01X769015Y279214D02*
G03X770143Y281937I-2722J2723D01*
G01D02*
Y292948D01*
G01X768061Y280170D02*
G03X768793Y281938I-1768J1768D01*
G01D02*
Y291086D01*
G01X770143Y292948D02*
G03X769500Y294500I-2195J0D01*
G01D02*
X769489Y294511D01*
G01D02*
G02Y298230I1860J1859D01*
G01X768793Y291086D02*
G03X768001Y292999I-2706J0D01*
G01D02*
X768000Y293000D01*
G01D02*
G03X765000I-1500J-1500D01*
G01D02*
G03Y290904I1048J-1048D01*
G01D02*
X765549Y290355D01*
G01X773762Y311866D02*
G03X772685Y309266I2601J-2601D01*
G01D02*
Y304890D01*
G01D02*
G02X772401Y304203I-971J-1D01*
G01D02*
X771447Y303250D01*
G01X757679Y315945D02*
X759102Y313104D01*
G01D02*
G02X758857Y312366I-492J-246D01*
G01D02*
X758856D01*
G01D02*
X758854Y312365D01*
G01D02*
Y312366D01*
G01D02*
G03X758852Y312363I1373J-917D01*
G01D02*
X758190Y312032D01*
G01D02*
G03X756935Y309266I2423J-2767D01*
G01D02*
Y304890D01*
G01X761614Y308070D02*
Y309739D01*
G01D02*
G03X760197Y311156I-1417J0D01*
G01D02*
X759558D01*
G01D02*
G03X758967Y310911I0J-836D01*
G01D02*
G03X758285Y309265I1646J-1646D01*
G01D02*
Y304890D01*
G01D02*
G03X758541Y304272I874J0D01*
G01D02*
X759563Y303250D01*
G01X816333Y285422D02*
X789188Y258277D01*
G01D02*
G02X786465Y257149I-2723J2722D01*
G01D02*
X779389D01*
G01D02*
G03X777621Y256417I0J-2500D01*
G01X815379Y286379D02*
X788232Y259232D01*
G01D02*
G02X786464Y258500I-1768J1768D01*
G01D02*
X779389D01*
G01D02*
G03X776666Y257372I0J-3850D01*
G01X775277Y263832D02*
G02X780872Y266150I5596J-5595D01*
G01D02*
X781999D01*
G01D02*
G03X784662Y267252I2J3764D01*
G01D02*
X798816Y281406D01*
G01X774322Y264787D02*
G02X780872Y267500I6550J-6550D01*
G01D02*
X782000D01*
G01D02*
G03X783707Y268207I0J2414D01*
G01D02*
X797861Y282361D01*
G01X784055Y283037D02*
G03X785903Y287500I-4463J4462D01*
G01X783100Y283992D02*
G03X784553Y287500I-3508J3508D01*
G01X785903D02*
Y296615D01*
G01D02*
G03X785234Y298230I-2284J0D01*
G01X784553Y287500D02*
Y291675D01*
G01D02*
G03X784002Y293005I-1881J0D01*
G01D02*
G03X781005I-1499J-1498D01*
G01D02*
X780616Y292616D01*
G01D02*
G03Y291038I789J-789D01*
G01D02*
X781299Y290355D01*
G01X789174Y315945D02*
X790597Y313104D01*
G01X790347Y312363D02*
X789685Y312032D01*
G01D02*
G03X788430Y309266I2423J-2767D01*
G01D02*
Y304890D01*
G01D02*
G02X788146Y304203I-971J-1D01*
G01D02*
X787192Y303250D01*
G01X773424Y315945D02*
Y315944D01*
G01D02*
X774479Y314889D01*
G01D02*
G02X775055Y313500I-1389J-1390D01*
G01D02*
G02X774685Y312684I-1084J0D01*
G01D02*
X773940Y312032D01*
G01D02*
G03X773762Y311866I2418J-2772D01*
G01X777364Y308070D02*
Y309739D01*
G01D02*
G03X775947Y311156I-1417J0D01*
G01D02*
X775308D01*
G01D02*
G03X774717Y310911I0J-836D01*
G01D02*
G03X774035Y309265I1646J-1646D01*
G01D02*
Y304890D01*
G01D02*
G03X774291Y304272I874J0D01*
G01D02*
X775313Y303250D01*
G01X798816Y281406D02*
G03X801754Y288500I-7094J7093D01*
G01X797861Y282361D02*
G03X800404Y288500I-6139J6139D01*
G01X801754D02*
Y291987D01*
G01D02*
G03X800819Y294246I-3194J1D01*
G01D02*
X799417Y295648D01*
G01D02*
G02Y297808I1080J1080D01*
G01D02*
G02X800436Y298230I1019J-1019D01*
G01D02*
X800984D01*
G01X800404Y288500D02*
Y291987D01*
G01D02*
G03X799864Y293291I-1844J0D01*
G01D02*
X799050Y294105D01*
G01D02*
G03X798478Y294424I-848J-848D01*
G01D02*
X797348D01*
G01D02*
G03X795849Y293803I0J-2120D01*
G01D02*
G03Y291555I1124J-1124D01*
G01D02*
X797049Y290355D01*
G01X804919Y315945D02*
X804960D01*
G01D02*
G02X806405Y314500I0J-1445D01*
G01X806241Y312737D02*
X805435Y312032D01*
G01D02*
G03X805257Y311866I2418J-2772D01*
G01D02*
G03X804180Y309266I2601J-2601D01*
G01D02*
Y304890D01*
G01D02*
G02X803896Y304203I-971J-1D01*
G01D02*
X802942Y303250D01*
G01X806212Y310911D02*
G03X805530Y309265I1646J-1646D01*
G01D02*
Y304890D01*
G01D02*
G03X805786Y304272I874J0D01*
G01D02*
X806808Y303250D01*
G01X790597Y313104D02*
G02X790352Y312366I-492J-246D01*
G01D02*
X790351D01*
G01D02*
X790349Y312365D01*
G01D02*
Y312366D01*
G01D02*
G03X790347Y312363I1373J-917D01*
G01X793109Y308070D02*
Y309739D01*
G01D02*
G03X791692Y311156I-1417J0D01*
G01D02*
X791053D01*
G01D02*
G03X790462Y310911I0J-836D01*
G01D02*
G03X789780Y309265I1646J-1646D01*
G01D02*
Y304890D01*
G01D02*
G03X790036Y304272I874J0D01*
G01D02*
X791058Y303250D01*
G01X817461Y288145D02*
G02X816333Y285422I-3850J0D01*
G01X816111Y288147D02*
G02X815379Y286379I-2500J0D01*
G01X816734Y298230D02*
G02X817486Y291808I-27046J-6422D01*
G01D02*
X817461Y291783D01*
G01D02*
Y288145D01*
G01X812794Y290355D02*
X812106Y291044D01*
G01D02*
G02X811091Y293493I2449J2450D01*
G01D02*
G02X814021Y294754I2167J-1001D01*
G01D02*
G02X816111Y292201I-994J-2946D01*
G01D02*
Y288147D01*
G01X806405Y314500D02*
Y313100D01*
G01D02*
G02X806241Y312737I-482J-1D01*
G01X808859Y308070D02*
X809055Y308266D01*
G01D02*
G03Y310500I-1117J1117D01*
G01D02*
G03X807471Y311156I-1584J-1584D01*
G01D02*
X806803D01*
G01D02*
G03X806212Y310911I0J-836D01*
G01X839141Y317270D02*
G02X837423Y315945I-1718J451D01*
G01D02*
X836419D01*
G01X838410Y336843D02*
Y335193D01*
G01D02*
G03X838805Y334403I990J1D01*
G01D02*
G02X839200Y333613I-595J-791D01*
G01Y331963D02*
G02X838805Y331173I-990J1D01*
G01D02*
G03X838410Y330383I595J-791D01*
G01D02*
Y328733D01*
G01D02*
G03X838805Y327943I990J1D01*
G01D02*
G02X839200Y327153I-595J-791D01*
G01Y325503D02*
G02X838805Y324713I-990J1D01*
G01D02*
G03X838410Y323923I595J-791D01*
G01D02*
Y322273D01*
G01D02*
G03X838805Y321483I990J1D01*
G01D02*
G02X839200Y320692I-595J-791D01*
G01Y344883D02*
G02X838805Y344093I-990J1D01*
G01D02*
G03X838410Y343303I595J-791D01*
G01D02*
Y341653D01*
G01D02*
G03X838805Y340863I990J1D01*
G01D02*
G02X839200Y340073I-595J-791D01*
G01Y338423D02*
G02X838805Y337633I-990J1D01*
G01D02*
G03X838410Y336843I595J-791D01*
G01X839200Y320692D02*
Y317722D01*
G01D02*
G02X839141Y317270I-1777J2D01*
G01X840550Y346532D02*
Y308543D01*
G01D02*
G02X840354Y308070I-669J0D01*
G01X839200Y333613D02*
Y331963D01*
G01Y327153D02*
Y325503D01*
G01X842090Y353510D02*
G03X839200Y346533I6978J-6978D01*
G01D02*
Y344883D01*
G01Y340073D02*
Y338423D01*
G01X843045Y352555D02*
G03X840550Y346532I6023J-6023D01*
G01X863740Y375160D02*
X842090Y353510D01*
G01X864695Y374205D02*
X843045Y352555D01*
G01X865040Y390231D02*
Y378298D01*
G01D02*
G02X863740Y375160I-4438J0D01*
G01X866390Y416200D02*
Y378297D01*
G01D02*
G02X864695Y374205I-5788J1D01*
G01X865040Y401501D02*
G02X864645Y400711I-990J1D01*
G01D02*
G03X864250Y399921I595J-791D01*
G01D02*
Y398271D01*
G01D02*
G03X864645Y397481I990J1D01*
G01D02*
G02X865040Y396691I-595J-791D01*
G01D02*
Y395041D01*
G01D02*
G02X864645Y394251I-990J1D01*
G01D02*
G03X864250Y393461I595J-791D01*
G01D02*
Y391811D01*
G01D02*
G03X864645Y391021I990J1D01*
G01D02*
G02X865040Y390231I-595J-791D01*
G01X873690Y424850D02*
G03X865040Y416200I0J-8650D01*
G01D02*
Y407961D01*
G01D02*
G02X864645Y407171I-990J1D01*
G01D02*
G03X864250Y406381I595J-791D01*
G01D02*
Y404731D01*
G01D02*
G03X864645Y403941I990J1D01*
G01D02*
G02X865040Y403151I-595J-791D01*
G01D02*
Y401501D01*
G01X873690Y423500D02*
G03X866390Y416200I0J-7300D01*
G01X903300Y424850D02*
X873690D01*
G01X903300Y423500D02*
X873690D01*
G01X909514Y427424D02*
G02X903300Y424850I-6214J6214D01*
G01X910469Y426469D02*
G02X903300Y423500I-7168J7169D01*
G01X919595Y437505D02*
X909514Y427424D01*
G01X920550Y436550D02*
X910469Y426469D01*
G01X924956Y439725D02*
G03X919595Y437505I-1J-7581D01*
G01X924956Y438375D02*
G03X920550Y436550I0J-6231D01*
G01X940045Y446955D02*
X934595Y441505D01*
G01D02*
G02X930298Y439725I-4297J4297D01*
G01D02*
X924956D01*
G01X941000Y446000D02*
X935550Y440550D01*
G01D02*
G02X930299Y438375I-5251J5252D01*
G01D02*
X924956D01*
G01X1030242Y449000D02*
X944982D01*
G01D02*
G03X940045Y446955I1J-6983D01*
G01X1030242Y447650D02*
X944983D01*
G01D02*
G03X941000Y446000I0J-5633D01*
G01X1034950Y450950D02*
G02X1030242Y449000I-4708J4708D01*
G01X1038605Y452695D02*
X1035905Y449995D01*
G01D02*
G02X1030242Y447650I-5662J5663D01*
G01X1037650Y453650D02*
X1034950Y450950D01*
G01X1198900Y457000D02*
X1045739D01*
G01D02*
G03X1037650Y453650I-1J-11439D01*
G01X1198901Y455650D02*
X1045739D01*
G01D02*
G03X1038605Y452695I0J-10089D01*
G01X1167414Y305565D02*
G03X1165000Y304565I0J-3414D01*
G01Y308175D02*
X1165383Y307792D01*
G01D02*
G03X1167500Y306915I2117J2117D01*
G01X1155500Y446892D02*
X1156162Y447555D01*
G01D02*
G02X1157600Y448150I1437J-1438D01*
G01D02*
X1198301D01*
G01X1155500Y450758D02*
X1156162Y450095D01*
G01D02*
G03X1157600Y449500I1437J1438D01*
G01D02*
X1198300D01*
G01X1184593Y304775D02*
X1182943D01*
G01D02*
G02X1182153Y305170I1J990D01*
G01D02*
G03X1181363Y305565I-791J-595D01*
G01D02*
X1179713D01*
G01D02*
G03X1178923Y305170I1J-990D01*
G01D02*
G02X1178133Y304775I-791J595D01*
G01D02*
X1176483D01*
G01D02*
G02X1175693Y305170I1J990D01*
G01D02*
G03X1174903Y305565I-791J-595D01*
G01D02*
X1167414D01*
G01X1167500Y306915D02*
X1214901D01*
G01X1200111Y304775D02*
X1198461D01*
G01D02*
G02X1197671Y305170I1J990D01*
G01D02*
G03X1196881Y305565I-791J-595D01*
G01D02*
X1192633D01*
G01D02*
G03X1191843Y305170I1J-990D01*
G01D02*
G02X1191053Y304775I-791J595D01*
G01D02*
X1189403D01*
G01D02*
G02X1188613Y305170I1J990D01*
G01D02*
G03X1187823Y305565I-791J-595D01*
G01D02*
X1186173D01*
G01D02*
G03X1185383Y305170I1J-990D01*
G01D02*
G02X1184593Y304775I-791J595D01*
G01X1198301Y448150D02*
G03X1207159Y451819I-1J12530D01*
G01X1198300Y449500D02*
G03X1206205Y452775I-1J11180D01*
G01X1206752Y460253D02*
G02X1198900Y457000I-7853J7852D01*
G01X1207702Y459293D02*
G02X1198901Y455650I-8802J8812D01*
G01X1220234Y303355D02*
G03X1214900Y305565I-5335J-5334D01*
G01D02*
X1208151D01*
G01D02*
G03X1207361Y305170I1J-990D01*
G01D02*
G02X1206571Y304775I-791J595D01*
G01D02*
X1204921D01*
G01D02*
G02X1204131Y305170I1J990D01*
G01D02*
G03X1203341Y305565I-791J-595D01*
G01D02*
X1201691D01*
G01D02*
G03X1200901Y305170I1J-990D01*
G01D02*
G02X1200111Y304775I-791J595D01*
G01X1214901Y306915D02*
G02X1221189Y304311I0J-8894D01*
G01X1207159Y451819D02*
X1207418Y452077D01*
G01D02*
X1246870Y491529D01*
G01X1206205Y452775D02*
X1206465Y453034D01*
G01D02*
X1245915Y492484D01*
G01X1246050Y499550D02*
X1206800Y460300D01*
G01D02*
X1206752Y460253D01*
G01X1247005Y498595D02*
X1207745Y459335D01*
G01D02*
X1207702Y459293D01*
G01X1233275Y290315D02*
G03X1232437Y290594I-699J-701D01*
G01D02*
G02X1231599Y290874I-138J980D01*
G01D02*
X1230433Y292040D01*
G01D02*
G02X1230153Y292878I700J700D01*
G01D02*
G03X1229874Y293716I-980J139D01*
G01D02*
X1228707Y294883D01*
G01D02*
G03X1227869Y295162I-699J-701D01*
G01D02*
G02X1227031Y295441I-139J981D01*
G01D02*
X1225865Y296608D01*
G01D02*
G02X1225585Y297446I700J700D01*
G01D02*
G03X1225306Y298284I-980J139D01*
G01D02*
X1220595Y302995D01*
G01D02*
X1220234Y303355D01*
G01X1221189Y304311D02*
X1244300Y281200D01*
G01X1253301Y278500D02*
X1247400D01*
G01D02*
Y278499D01*
G01D02*
G02X1243455Y280134I0J5576D01*
G01D02*
X1243341Y280249D01*
G01D02*
X1237843Y285747D01*
G01D02*
G03X1237005Y286026I-699J-701D01*
G01D02*
G02X1236167Y286306I-138J980D01*
G01D02*
X1235000Y287472D01*
G01X1244300Y281200D02*
X1244412Y281087D01*
G01D02*
G03X1247400Y279850I2987J2988D01*
G01D02*
X1253301D01*
G01X1235000Y287472D02*
G02X1234721Y288310I702J699D01*
G01D02*
G03X1234442Y289148I-980J139D01*
G01D02*
X1233275Y290315D01*
G01X1246870Y491529D02*
G02X1252836Y494000I5966J-5966D01*
G01X1245915Y492484D02*
G02X1252836Y495350I6920J-6921D01*
G01X1252810Y502350D02*
G03X1246050Y499550I0J-9561D01*
G01X1252811Y501000D02*
G03X1247005Y498595I0J-8211D01*
G01X1258851Y271776D02*
G02X1256900Y269825I-1951J0D01*
G01D02*
X1256430D01*
G01D02*
G03X1256041Y269664I0J-550D01*
G01D02*
X1254944Y268567D01*
G01Y272433D02*
X1256041Y271336D01*
G01D02*
G03X1256430Y271175I389J389D01*
G01D02*
X1256900D01*
G01D02*
G03X1257501Y271776I0J601D01*
G01D02*
Y274300D01*
G01D02*
G03X1253301Y278500I-4200J0D01*
G01Y279850D02*
G02X1258851Y274300I0J-5550D01*
G01D02*
Y271776D01*
G01X1252836Y494000D02*
X1327600D01*
G01X1252836Y495350D02*
X1327600D01*
G01X1275600Y502350D02*
X1252810D01*
G01X1275600Y501000D02*
X1252811D01*
G01X1282326Y505136D02*
G02X1275600Y502350I-6726J6726D01*
G01X1283281Y504181D02*
G02X1275600Y501000I-7680J7681D01*
G01X1304447Y527257D02*
X1282326Y505136D01*
G01X1305400Y526300D02*
X1283281Y504181D01*
G01X1332232Y529600D02*
X1309699D01*
G01D02*
G03X1304735Y527544I1J-7023D01*
G01D02*
X1304447Y527257D01*
G01X1332400Y528250D02*
X1309700D01*
G01D02*
G03X1305689Y526588I1J-5673D01*
G01D02*
X1305400Y526300D01*
G01X1327600Y494000D02*
G03X1335298Y497188I1J10886D01*
G01X1327600Y495350D02*
G03X1334343Y498143I0J9536D01*
G01X1330517Y525012D02*
X1323312D01*
G01D02*
X1322900Y524600D01*
G01X1330517Y533012D02*
X1322488D01*
G01D02*
X1322400Y533100D01*
G01X1335298Y497188D02*
X1357936Y519826D01*
G01X1334343Y498143D02*
X1356981Y520781D01*
G01X1354700Y529687D02*
X1345800D01*
G01D02*
G02X1344600Y530887I0J1200D01*
G01D02*
Y532100D01*
G01D02*
G03X1343688Y533012I-912J0D01*
G01X1354700Y528337D02*
X1345800D01*
G01D02*
G03X1344700Y527237I0J-1100D01*
G01D02*
Y525600D01*
G01D02*
G02X1344112Y525012I-588J0D01*
G01D02*
X1342017D01*
G01X1347517D02*
X1351488D01*
G01X1334212Y533012D02*
G03X1333300Y532100I0J-912D01*
G01D02*
Y530668D01*
G01D02*
G02X1332232Y529600I-1068J0D01*
G01X1336017Y525012D02*
X1336517D01*
G01X1336017D02*
X1334488D01*
G01D02*
G02X1333400Y526100I0J1088D01*
G01D02*
Y527250D01*
G01D02*
G03X1332400Y528250I-1000J0D01*
G01X1343688Y533012D02*
X1342017D01*
G01X1347517D02*
X1351812D01*
G01X1336017D02*
X1336517D01*
G01X1336017D02*
X1334212D01*
G01X1357936Y519826D02*
G03X1359250Y523000I-3175J3173D01*
G01D02*
Y525137D01*
G01D02*
G03X1354700Y529687I-4550J0D01*
G01X1356981Y520781D02*
G03X1357900Y523000I-2219J2219D01*
G01D02*
Y525137D01*
G01D02*
G03X1354700Y528337I-3200J0D01*
G01X1351488Y525012D02*
X1351900Y524600D01*
G01X1351812Y533012D02*
X1352400Y533600D01*
M02*
